(kicad_sch (version 20230121) (generator eeschema)

  (paper "A3")

  (title_block
    (title "ECP5 - Datacenter Secure Control Module (DC-SCM)")
    (date "2024-07-15")
    (rev "1.2.1")
  )

  (junction (at 396.24 46.99) (diameter 0) (color 0 0 0 0)
  )
  (junction (at 72.39 276.86) (diameter 0) (color 0 0 0 0)
  )
  (junction (at 388.62 229.87) (diameter 0) (color 0 0 0 0)
  )
  (junction (at 135.89 60.96) (diameter 0) (color 0 0 0 0)
  )
  (junction (at 323.85 116.84) (diameter 0) (color 0 0 0 0)
  )
  (junction (at 58.42 229.87) (diameter 0) (color 0 0 0 0)
  )
  (junction (at 59.69 276.86) (diameter 0) (color 0 0 0 0)
  )
  (junction (at 314.96 116.84) (diameter 0) (color 0 0 0 0)
  )
  (junction (at 298.45 116.84) (diameter 0) (color 0 0 0 0)
  )
  (junction (at 115.57 26.67) (diameter 0) (color 0 0 0 0)
  )
  (junction (at 151.13 220.98) (diameter 0) (color 0 0 0 0)
  )
  (junction (at 168.91 265.43) (diameter 0) (color 0 0 0 0)
  )
  (junction (at 355.6 227.33) (diameter 0) (color 0 0 0 0)
  )
  (junction (at 81.28 252.73) (diameter 0) (color 0 0 0 0)
  )
  (junction (at 306.07 129.54) (diameter 0) (color 0 0 0 0)
  )
  (junction (at 132.08 26.67) (diameter 0) (color 0 0 0 0)
  )
  (junction (at 166.37 76.2) (diameter 0) (color 0 0 0 0)
  )
  (junction (at 160.02 220.98) (diameter 0) (color 0 0 0 0)
  )
  (junction (at 316.23 52.07) (diameter 0) (color 0 0 0 0)
  )
  (junction (at 307.34 39.37) (diameter 0) (color 0 0 0 0)
  )
  (junction (at 325.12 39.37) (diameter 0) (color 0 0 0 0)
  )
  (junction (at 129.54 242.57) (diameter 0) (color 0 0 0 0)
  )
  (junction (at 388.62 133.35) (diameter 0) (color 0 0 0 0)
  )
  (junction (at 156.21 257.81) (diameter 0) (color 0 0 0 0)
  )
  (junction (at 156.21 60.96) (diameter 0) (color 0 0 0 0)
  )
  (junction (at 386.08 227.33) (diameter 0) (color 0 0 0 0)
  )
  (junction (at 314.96 129.54) (diameter 0) (color 0 0 0 0)
  )
  (junction (at 76.2 219.71) (diameter 0) (color 0 0 0 0)
  )
  (junction (at 172.72 76.2) (diameter 0) (color 0 0 0 0)
  )
  (junction (at 306.07 116.84) (diameter 0) (color 0 0 0 0)
  )
  (junction (at 96.52 265.43) (diameter 0) (color 0 0 0 0)
  )
  (junction (at 289.56 39.37) (diameter 0) (color 0 0 0 0)
  )
  (junction (at 53.34 276.86) (diameter 0) (color 0 0 0 0)
  )
  (junction (at 355.6 229.87) (diameter 0) (color 0 0 0 0)
  )
  (junction (at 66.04 167.64) (diameter 0) (color 0 0 0 0)
  )
  (junction (at 71.12 167.64) (diameter 0) (color 0 0 0 0)
  )
  (junction (at 138.43 220.98) (diameter 0) (color 0 0 0 0)
  )
  (junction (at 388.62 118.11) (diameter 0) (color 0 0 0 0)
  )
  (junction (at 153.67 22.86) (diameter 0) (color 0 0 0 0)
  )
  (junction (at 147.32 252.73) (diameter 0) (color 0 0 0 0)
  )
  (junction (at 375.92 222.25) (diameter 0) (color 0 0 0 0)
  )
  (junction (at 289.56 52.07) (diameter 0) (color 0 0 0 0)
  )
  (junction (at 58.42 167.64) (diameter 0) (color 0 0 0 0)
  )
  (junction (at 142.24 250.19) (diameter 0) (color 0 0 0 0)
  )
  (junction (at 151.13 255.27) (diameter 0) (color 0 0 0 0)
  )
  (junction (at 50.8 229.87) (diameter 0) (color 0 0 0 0)
  )
  (junction (at 123.19 26.67) (diameter 0) (color 0 0 0 0)
  )
  (junction (at 156.21 220.98) (diameter 0) (color 0 0 0 0)
  )
  (junction (at 290.83 167.64) (diameter 0) (color 0 0 0 0)
  )
  (junction (at 137.16 46.99) (diameter 0) (color 0 0 0 0)
  )
  (junction (at 50.8 219.71) (diameter 0) (color 0 0 0 0)
  )
  (junction (at 394.97 30.48) (diameter 0) (color 0 0 0 0)
  )
  (junction (at 355.6 234.95) (diameter 0) (color 0 0 0 0)
  )
  (junction (at 397.51 140.97) (diameter 0) (color 0 0 0 0)
  )
  (junction (at 323.85 129.54) (diameter 0) (color 0 0 0 0)
  )
  (junction (at 397.51 125.73) (diameter 0) (color 0 0 0 0)
  )
  (junction (at 138.43 247.65) (diameter 0) (color 0 0 0 0)
  )
  (junction (at 355.6 222.25) (diameter 0) (color 0 0 0 0)
  )
  (junction (at 316.23 39.37) (diameter 0) (color 0 0 0 0)
  )
  (junction (at 53.34 261.62) (diameter 0) (color 0 0 0 0)
  )
  (junction (at 295.91 81.28) (diameter 0) (color 0 0 0 0)
  )
  (junction (at 133.35 245.11) (diameter 0) (color 0 0 0 0)
  )
  (junction (at 298.45 129.54) (diameter 0) (color 0 0 0 0)
  )
  (junction (at 66.04 276.86) (diameter 0) (color 0 0 0 0)
  )
  (junction (at 142.24 105.41) (diameter 0) (color 0 0 0 0)
  )
  (junction (at 63.5 167.64) (diameter 0) (color 0 0 0 0)
  )
  (junction (at 66.04 261.62) (diameter 0) (color 0 0 0 0)
  )
  (junction (at 133.35 220.98) (diameter 0) (color 0 0 0 0)
  )
  (junction (at 97.79 170.18) (diameter 0) (color 0 0 0 0)
  )
  (junction (at 142.24 220.98) (diameter 0) (color 0 0 0 0)
  )
  (junction (at 160.02 260.35) (diameter 0) (color 0 0 0 0)
  )
  (junction (at 194.31 45.72) (diameter 0) (color 0 0 0 0)
  )
  (junction (at 134.62 105.41) (diameter 0) (color 0 0 0 0)
  )
  (junction (at 67.31 229.87) (diameter 0) (color 0 0 0 0)
  )
  (junction (at 143.51 60.96) (diameter 0) (color 0 0 0 0)
  )
  (junction (at 147.32 220.98) (diameter 0) (color 0 0 0 0)
  )
  (junction (at 161.29 22.86) (diameter 0) (color 0 0 0 0)
  )
  (junction (at 298.45 52.07) (diameter 0) (color 0 0 0 0)
  )
  (junction (at 60.96 167.64) (diameter 0) (color 0 0 0 0)
  )
  (junction (at 97.79 240.03) (diameter 0) (color 0 0 0 0)
  )
  (junction (at 165.1 262.89) (diameter 0) (color 0 0 0 0)
  )
  (junction (at 168.91 220.98) (diameter 0) (color 0 0 0 0)
  )
  (junction (at 168.91 22.86) (diameter 0) (color 0 0 0 0)
  )
  (junction (at 46.99 261.62) (diameter 0) (color 0 0 0 0)
  )
  (junction (at 331.47 116.84) (diameter 0) (color 0 0 0 0)
  )
  (junction (at 405.13 55.88) (diameter 0) (color 0 0 0 0)
  )
  (junction (at 307.34 52.07) (diameter 0) (color 0 0 0 0)
  )
  (junction (at 97.79 161.29) (diameter 0) (color 0 0 0 0)
  )
  (junction (at 355.6 224.79) (diameter 0) (color 0 0 0 0)
  )
  (junction (at 72.39 261.62) (diameter 0) (color 0 0 0 0)
  )
  (junction (at 355.6 232.41) (diameter 0) (color 0 0 0 0)
  )
  (junction (at 76.2 229.87) (diameter 0) (color 0 0 0 0)
  )
  (junction (at 194.31 39.37) (diameter 0) (color 0 0 0 0)
  )
  (junction (at 403.86 38.1) (diameter 0) (color 0 0 0 0)
  )
  (junction (at 298.45 39.37) (diameter 0) (color 0 0 0 0)
  )
  (junction (at 45.72 52.07) (diameter 0) (color 0 0 0 0)
  )
  (junction (at 46.99 276.86) (diameter 0) (color 0 0 0 0)
  )
  (junction (at 144.78 46.99) (diameter 0) (color 0 0 0 0)
  )
  (junction (at 250.19 121.92) (diameter 0) (color 0 0 0 0)
  )
  (junction (at 59.69 261.62) (diameter 0) (color 0 0 0 0)
  )
  (junction (at 68.58 167.64) (diameter 0) (color 0 0 0 0)
  )
  (junction (at 58.42 219.71) (diameter 0) (color 0 0 0 0)
  )
  (junction (at 67.31 219.71) (diameter 0) (color 0 0 0 0)
  )
  (junction (at 73.66 167.64) (diameter 0) (color 0 0 0 0)
  )
  (junction (at 194.31 130.81) (diameter 0) (color 0 0 0 0)
  )
  (junction (at 176.53 22.86) (diameter 0) (color 0 0 0 0)
  )
  (junction (at 91.44 161.29) (diameter 0) (color 0 0 0 0)
  )
  (junction (at 378.46 224.79) (diameter 0) (color 0 0 0 0)
  )
  (junction (at 81.28 245.11) (diameter 0) (color 0 0 0 0)
  )
  (junction (at 165.1 220.98) (diameter 0) (color 0 0 0 0)
  )

  (no_connect (at 237.49 85.09))
  (no_connect (at 196.85 88.9))
  (no_connect (at 346.71 78.74))
  (no_connect (at 237.49 76.2))
  (no_connect (at 345.44 153.67))
  (no_connect (at 237.49 49.53))
  (no_connect (at 237.49 71.12))
  (no_connect (at 120.65 199.39))
  (no_connect (at 237.49 92.71))
  (no_connect (at 237.49 95.25))
  (no_connect (at 237.49 57.15))
  (no_connect (at 237.49 87.63))
  (no_connect (at 381 237.49))
  (no_connect (at 346.71 64.77))
  (no_connect (at 237.49 78.74))
  (no_connect (at 368.3 232.41))
  (no_connect (at 196.85 83.82))
  (no_connect (at 237.49 116.84))
  (no_connect (at 237.49 111.76))
  (no_connect (at 345.44 165.1))
  (no_connect (at 237.49 82.55))
  (no_connect (at 237.49 60.96))
  (no_connect (at 237.49 90.17))
  (no_connect (at 346.71 59.69))
  (no_connect (at 237.49 114.3))
  (no_connect (at 346.71 67.31))
  (no_connect (at 237.49 63.5))
  (no_connect (at 345.44 151.13))
  (no_connect (at 237.49 68.58))
  (no_connect (at 237.49 109.22))
  (no_connect (at 383.54 237.49))
  (no_connect (at 237.49 100.33))
  (no_connect (at 237.49 97.79))
  (no_connect (at 237.49 119.38))
  (no_connect (at 237.49 104.14))
  (no_connect (at 368.3 234.95))
  (no_connect (at 237.49 73.66))
  (no_connect (at 196.85 86.36))
  (no_connect (at 237.49 52.07))
  (no_connect (at 237.49 54.61))
  (no_connect (at 237.49 66.04))
  (no_connect (at 345.44 146.05))
  (no_connect (at 196.85 99.06))
  (no_connect (at 237.49 106.68))

  (wire (pts (xy 96.52 265.43) (xy 96.52 269.24))
    (stroke (width 0) (type default))
  )
  (wire (pts (xy 377.19 130.81) (xy 377.19 118.11))
    (stroke (width 0) (type default))
  )
  (wire (pts (xy 237.49 46.99) (xy 250.19 46.99))
    (stroke (width 0) (type default))
  )
  (wire (pts (xy 74.93 261.62) (xy 72.39 261.62))
    (stroke (width 0) (type default))
  )
  (wire (pts (xy 314.96 119.38) (xy 314.96 116.84))
    (stroke (width 0) (type default))
  )
  (wire (pts (xy 298.45 116.84) (xy 306.07 116.84))
    (stroke (width 0) (type default))
  )
  (wire (pts (xy 405.13 57.15) (xy 405.13 55.88))
    (stroke (width 0) (type default))
  )
  (wire (pts (xy 345.44 130.81) (xy 337.82 130.81))
    (stroke (width 0) (type default))
  )
  (wire (pts (xy 322.58 214.63) (xy 323.85 214.63))
    (stroke (width 0) (type default))
  )
  (wire (pts (xy 151.13 255.27) (xy 173.99 255.27))
    (stroke (width 0) (type default))
  )
  (wire (pts (xy 137.16 46.99) (xy 144.78 46.99))
    (stroke (width 0) (type default))
  )
  (wire (pts (xy 168.91 22.86) (xy 168.91 24.13))
    (stroke (width 0) (type default))
  )
  (wire (pts (xy 306.07 129.54) (xy 314.96 129.54))
    (stroke (width 0) (type default))
  )
  (wire (pts (xy 355.6 229.87) (xy 355.6 232.41))
    (stroke (width 0) (type default))
  )
  (wire (pts (xy 358.14 222.25) (xy 355.6 222.25))
    (stroke (width 0) (type default))
  )
  (wire (pts (xy 394.97 31.75) (xy 394.97 30.48))
    (stroke (width 0) (type default))
  )
  (wire (pts (xy 388.62 134.62) (xy 388.62 133.35))
    (stroke (width 0) (type default))
  )
  (wire (pts (xy 132.08 34.29) (xy 132.08 36.83))
    (stroke (width 0) (type default))
  )
  (wire (pts (xy 166.37 76.2) (xy 172.72 76.2))
    (stroke (width 0) (type default))
  )
  (wire (pts (xy 346.71 87.63) (xy 345.44 87.63))
    (stroke (width 0) (type default))
  )
  (wire (pts (xy 72.39 276.86) (xy 72.39 278.13))
    (stroke (width 0) (type default))
  )
  (wire (pts (xy 314.96 116.84) (xy 323.85 116.84))
    (stroke (width 0) (type default))
  )
  (wire (pts (xy 374.65 153.67) (xy 369.57 153.67))
    (stroke (width 0) (type default))
  )
  (wire (pts (xy 100.33 190.5) (xy 97.79 190.5))
    (stroke (width 0) (type default))
  )
  (wire (pts (xy 74.93 245.11) (xy 81.28 245.11))
    (stroke (width 0) (type default))
  )
  (wire (pts (xy 144.78 46.99) (xy 144.78 48.26))
    (stroke (width 0) (type default))
  )
  (wire (pts (xy 72.39 276.86) (xy 66.04 276.86))
    (stroke (width 0) (type default))
  )
  (wire (pts (xy 144.78 22.86) (xy 153.67 22.86))
    (stroke (width 0) (type default))
  )
  (wire (pts (xy 81.28 243.84) (xy 81.28 245.11))
    (stroke (width 0) (type default))
  )
  (wire (pts (xy 234.95 215.9) (xy 229.87 215.9))
    (stroke (width 0) (type default))
  )
  (wire (pts (xy 146.05 189.23) (xy 146.05 191.77))
    (stroke (width 0) (type default))
  )
  (wire (pts (xy 67.31 227.33) (xy 67.31 229.87))
    (stroke (width 0) (type default))
  )
  (wire (pts (xy 355.6 219.71) (xy 358.14 219.71))
    (stroke (width 0) (type default))
  )
  (wire (pts (xy 307.34 39.37) (xy 307.34 43.18))
    (stroke (width 0) (type default))
  )
  (wire (pts (xy 120.65 201.93) (xy 121.92 201.93))
    (stroke (width 0) (type default))
  )
  (wire (pts (xy 336.55 85.09) (xy 336.55 91.44))
    (stroke (width 0) (type default))
  )
  (wire (pts (xy 397.51 134.62) (xy 397.51 133.35))
    (stroke (width 0) (type default))
  )
  (wire (pts (xy 134.62 105.41) (xy 142.24 105.41))
    (stroke (width 0) (type default))
  )
  (wire (pts (xy 341.63 54.61) (xy 346.71 54.61))
    (stroke (width 0) (type default))
  )
  (wire (pts (xy 234.95 241.3) (xy 234.95 238.76))
    (stroke (width 0) (type default))
  )
  (wire (pts (xy 115.57 34.29) (xy 115.57 36.83))
    (stroke (width 0) (type default))
  )
  (wire (pts (xy 375.92 67.31) (xy 370.84 67.31))
    (stroke (width 0) (type default))
  )
  (wire (pts (xy 368.3 227.33) (xy 386.08 227.33))
    (stroke (width 0) (type default))
  )
  (wire (pts (xy 129.54 220.98) (xy 133.35 220.98))
    (stroke (width 0) (type default))
  )
  (wire (pts (xy 250.19 107.95) (xy 254 107.95))
    (stroke (width 0) (type default))
  )
  (wire (pts (xy 391.16 236.22) (xy 398.78 236.22))
    (stroke (width 0) (type default))
  )
  (wire (pts (xy 336.55 85.09) (xy 339.09 85.09))
    (stroke (width 0) (type default))
  )
  (wire (pts (xy 58.42 176.53) (xy 58.42 189.23))
    (stroke (width 0) (type default))
  )
  (wire (pts (xy 74.93 251.46) (xy 74.93 252.73))
    (stroke (width 0) (type default))
  )
  (wire (pts (xy 43.18 227.33) (xy 43.18 229.87))
    (stroke (width 0) (type default))
  )
  (wire (pts (xy 307.34 39.37) (xy 316.23 39.37))
    (stroke (width 0) (type default))
  )
  (wire (pts (xy 71.12 185.42) (xy 71.12 201.93))
    (stroke (width 0) (type default))
  )
  (wire (pts (xy 375.92 62.23) (xy 370.84 62.23))
    (stroke (width 0) (type default))
  )
  (wire (pts (xy 142.24 26.67) (xy 142.24 45.72))
    (stroke (width 0) (type default))
  )
  (wire (pts (xy 137.16 46.99) (xy 137.16 48.26))
    (stroke (width 0) (type default))
  )
  (wire (pts (xy 325.12 39.37) (xy 331.47 39.37))
    (stroke (width 0) (type default))
  )
  (wire (pts (xy 166.37 83.82) (xy 166.37 85.09))
    (stroke (width 0) (type default))
  )
  (wire (pts (xy 156.21 220.98) (xy 160.02 220.98))
    (stroke (width 0) (type default))
  )
  (wire (pts (xy 134.62 105.41) (xy 134.62 106.68))
    (stroke (width 0) (type default))
  )
  (wire (pts (xy 370.84 46.99) (xy 396.24 46.99))
    (stroke (width 0) (type default))
  )
  (wire (pts (xy 160.02 260.35) (xy 173.99 260.35))
    (stroke (width 0) (type default))
  )
  (wire (pts (xy 40.64 276.86) (xy 46.99 276.86))
    (stroke (width 0) (type default))
  )
  (wire (pts (xy 53.34 273.05) (xy 53.34 276.86))
    (stroke (width 0) (type default))
  )
  (wire (pts (xy 58.42 227.33) (xy 58.42 229.87))
    (stroke (width 0) (type default))
  )
  (wire (pts (xy 153.67 22.86) (xy 153.67 24.13))
    (stroke (width 0) (type default))
  )
  (wire (pts (xy 120.65 180.34) (xy 123.19 180.34))
    (stroke (width 0) (type default))
  )
  (wire (pts (xy 153.67 22.86) (xy 161.29 22.86))
    (stroke (width 0) (type default))
  )
  (wire (pts (xy 289.56 48.26) (xy 289.56 52.07))
    (stroke (width 0) (type default))
  )
  (wire (pts (xy 151.13 220.98) (xy 156.21 220.98))
    (stroke (width 0) (type default))
  )
  (wire (pts (xy 53.34 261.62) (xy 46.99 261.62))
    (stroke (width 0) (type default))
  )
  (wire (pts (xy 394.97 38.1) (xy 403.86 38.1))
    (stroke (width 0) (type default))
  )
  (wire (pts (xy 133.35 233.68) (xy 133.35 245.11))
    (stroke (width 0) (type default))
  )
  (wire (pts (xy 237.49 129.54) (xy 238.76 129.54))
    (stroke (width 0) (type default))
  )
  (wire (pts (xy 120.65 185.42) (xy 123.19 185.42))
    (stroke (width 0) (type default))
  )
  (wire (pts (xy 306.07 124.46) (xy 306.07 129.54))
    (stroke (width 0) (type default))
  )
  (wire (pts (xy 166.37 76.2) (xy 166.37 78.74))
    (stroke (width 0) (type default))
  )
  (wire (pts (xy 123.19 34.29) (xy 123.19 36.83))
    (stroke (width 0) (type default))
  )
  (wire (pts (xy 143.51 60.96) (xy 156.21 60.96))
    (stroke (width 0) (type default))
  )
  (wire (pts (xy 396.24 46.99) (xy 396.24 49.53))
    (stroke (width 0) (type default))
  )
  (wire (pts (xy 358.14 232.41) (xy 355.6 232.41))
    (stroke (width 0) (type default))
  )
  (wire (pts (xy 243.84 248.92) (xy 246.38 248.92))
    (stroke (width 0) (type default))
  )
  (wire (pts (xy 298.45 48.26) (xy 298.45 52.07))
    (stroke (width 0) (type default))
  )
  (wire (pts (xy 100.33 187.96) (xy 97.79 187.96))
    (stroke (width 0) (type default))
  )
  (wire (pts (xy 81.28 252.73) (xy 81.28 254))
    (stroke (width 0) (type default))
  )
  (wire (pts (xy 294.64 81.28) (xy 295.91 81.28))
    (stroke (width 0) (type default))
  )
  (wire (pts (xy 63.5 176.53) (xy 63.5 194.31))
    (stroke (width 0) (type default))
  )
  (wire (pts (xy 80.01 161.29) (xy 83.82 161.29))
    (stroke (width 0) (type default))
  )
  (wire (pts (xy 147.32 49.53) (xy 196.85 49.53))
    (stroke (width 0) (type default))
  )
  (wire (pts (xy 40.64 52.07) (xy 45.72 52.07))
    (stroke (width 0) (type default))
  )
  (wire (pts (xy 97.79 160.02) (xy 97.79 161.29))
    (stroke (width 0) (type default))
  )
  (wire (pts (xy 226.06 270.51) (xy 226.06 273.05))
    (stroke (width 0) (type default))
  )
  (wire (pts (xy 344.17 85.09) (xy 346.71 85.09))
    (stroke (width 0) (type default))
  )
  (wire (pts (xy 388.62 139.7) (xy 388.62 140.97))
    (stroke (width 0) (type default))
  )
  (wire (pts (xy 71.12 167.64) (xy 73.66 167.64))
    (stroke (width 0) (type default))
  )
  (wire (pts (xy 120.65 182.88) (xy 123.19 182.88))
    (stroke (width 0) (type default))
  )
  (wire (pts (xy 68.58 199.39) (xy 55.88 199.39))
    (stroke (width 0) (type default))
  )
  (wire (pts (xy 298.45 52.07) (xy 307.34 52.07))
    (stroke (width 0) (type default))
  )
  (wire (pts (xy 375.92 52.07) (xy 370.84 52.07))
    (stroke (width 0) (type default))
  )
  (wire (pts (xy 76.2 167.64) (xy 76.2 180.34))
    (stroke (width 0) (type default))
  )
  (wire (pts (xy 368.3 219.71) (xy 393.7 219.71))
    (stroke (width 0) (type default))
  )
  (wire (pts (xy 297.18 83.82) (xy 295.91 83.82))
    (stroke (width 0) (type default))
  )
  (wire (pts (xy 289.56 39.37) (xy 298.45 39.37))
    (stroke (width 0) (type default))
  )
  (wire (pts (xy 144.78 46.99) (xy 147.32 46.99))
    (stroke (width 0) (type default))
  )
  (wire (pts (xy 73.66 176.53) (xy 73.66 204.47))
    (stroke (width 0) (type default))
  )
  (wire (pts (xy 396.24 54.61) (xy 396.24 55.88))
    (stroke (width 0) (type default))
  )
  (wire (pts (xy 388.62 237.49) (xy 388.62 229.87))
    (stroke (width 0) (type default))
  )
  (wire (pts (xy 292.1 172.72) (xy 290.83 172.72))
    (stroke (width 0) (type default))
  )
  (wire (pts (xy 161.29 22.86) (xy 168.91 22.86))
    (stroke (width 0) (type default))
  )
  (wire (pts (xy 97.79 170.18) (xy 100.33 170.18))
    (stroke (width 0) (type default))
  )
  (wire (pts (xy 74.93 252.73) (xy 81.28 252.73))
    (stroke (width 0) (type default))
  )
  (wire (pts (xy 168.91 233.68) (xy 168.91 265.43))
    (stroke (width 0) (type default))
  )
  (wire (pts (xy 298.45 119.38) (xy 298.45 116.84))
    (stroke (width 0) (type default))
  )
  (wire (pts (xy 88.9 161.29) (xy 91.44 161.29))
    (stroke (width 0) (type default))
  )
  (wire (pts (xy 97.79 240.03) (xy 97.79 242.57))
    (stroke (width 0) (type default))
  )
  (wire (pts (xy 100.33 240.03) (xy 97.79 240.03))
    (stroke (width 0) (type default))
  )
  (wire (pts (xy 316.23 39.37) (xy 316.23 43.18))
    (stroke (width 0) (type default))
  )
  (wire (pts (xy 156.21 233.68) (xy 156.21 257.81))
    (stroke (width 0) (type default))
  )
  (wire (pts (xy 161.29 29.21) (xy 161.29 31.75))
    (stroke (width 0) (type default))
  )
  (wire (pts (xy 322.58 227.33) (xy 322.58 229.87))
    (stroke (width 0) (type default))
  )
  (wire (pts (xy 391.16 237.49) (xy 391.16 236.22))
    (stroke (width 0) (type default))
  )
  (wire (pts (xy 322.58 219.71) (xy 323.85 219.71))
    (stroke (width 0) (type default))
  )
  (wire (pts (xy 67.31 48.26) (xy 67.31 49.53))
    (stroke (width 0) (type default))
  )
  (wire (pts (xy 120.65 255.27) (xy 151.13 255.27))
    (stroke (width 0) (type default))
  )
  (wire (pts (xy 344.17 173.99) (xy 345.44 173.99))
    (stroke (width 0) (type default))
  )
  (wire (pts (xy 81.28 246.38) (xy 81.28 245.11))
    (stroke (width 0) (type default))
  )
  (wire (pts (xy 335.28 171.45) (xy 335.28 179.07))
    (stroke (width 0) (type default))
  )
  (wire (pts (xy 100.33 182.88) (xy 97.79 182.88))
    (stroke (width 0) (type default))
  )
  (wire (pts (xy 97.79 170.18) (xy 97.79 161.29))
    (stroke (width 0) (type default))
  )
  (wire (pts (xy 194.31 128.27) (xy 194.31 130.81))
    (stroke (width 0) (type default))
  )
  (wire (pts (xy 55.88 194.31) (xy 63.5 194.31))
    (stroke (width 0) (type default))
  )
  (wire (pts (xy 58.42 189.23) (xy 55.88 189.23))
    (stroke (width 0) (type default))
  )
  (wire (pts (xy 113.03 46.99) (xy 121.92 46.99))
    (stroke (width 0) (type default))
  )
  (wire (pts (xy 143.51 110.49) (xy 142.24 110.49))
    (stroke (width 0) (type default))
  )
  (wire (pts (xy 266.7 170.18) (xy 266.7 171.45))
    (stroke (width 0) (type default))
  )
  (wire (pts (xy 176.53 29.21) (xy 176.53 31.75))
    (stroke (width 0) (type default))
  )
  (wire (pts (xy 290.83 172.72) (xy 290.83 173.99))
    (stroke (width 0) (type default))
  )
  (wire (pts (xy 132.08 26.67) (xy 132.08 29.21))
    (stroke (width 0) (type default))
  )
  (wire (pts (xy 132.08 26.67) (xy 142.24 26.67))
    (stroke (width 0) (type default))
  )
  (wire (pts (xy 46.99 261.62) (xy 46.99 267.97))
    (stroke (width 0) (type default))
  )
  (wire (pts (xy 369.57 161.29) (xy 374.65 161.29))
    (stroke (width 0) (type default))
  )
  (wire (pts (xy 147.32 220.98) (xy 151.13 220.98))
    (stroke (width 0) (type default))
  )
  (wire (pts (xy 396.24 55.88) (xy 405.13 55.88))
    (stroke (width 0) (type default))
  )
  (wire (pts (xy 81.28 245.11) (xy 100.33 245.11))
    (stroke (width 0) (type default))
  )
  (wire (pts (xy 129.54 233.68) (xy 129.54 242.57))
    (stroke (width 0) (type default))
  )
  (wire (pts (xy 144.78 53.34) (xy 144.78 54.61))
    (stroke (width 0) (type default))
  )
  (wire (pts (xy 405.13 46.99) (xy 405.13 48.26))
    (stroke (width 0) (type default))
  )
  (wire (pts (xy 355.6 224.79) (xy 355.6 227.33))
    (stroke (width 0) (type default))
  )
  (wire (pts (xy 168.91 29.21) (xy 168.91 31.75))
    (stroke (width 0) (type default))
  )
  (wire (pts (xy 45.72 36.83) (xy 40.64 36.83))
    (stroke (width 0) (type default))
  )
  (wire (pts (xy 66.04 276.86) (xy 59.69 276.86))
    (stroke (width 0) (type default))
  )
  (wire (pts (xy 76.2 227.33) (xy 76.2 229.87))
    (stroke (width 0) (type default))
  )
  (wire (pts (xy 162.56 105.41) (xy 175.26 105.41))
    (stroke (width 0) (type default))
  )
  (wire (pts (xy 397.51 125.73) (xy 397.51 127))
    (stroke (width 0) (type default))
  )
  (wire (pts (xy 97.79 172.72) (xy 97.79 170.18))
    (stroke (width 0) (type default))
  )
  (wire (pts (xy 120.65 247.65) (xy 138.43 247.65))
    (stroke (width 0) (type default))
  )
  (wire (pts (xy 66.04 273.05) (xy 66.04 276.86))
    (stroke (width 0) (type default))
  )
  (wire (pts (xy 156.21 59.69) (xy 156.21 60.96))
    (stroke (width 0) (type default))
  )
  (wire (pts (xy 316.23 39.37) (xy 325.12 39.37))
    (stroke (width 0) (type default))
  )
  (wire (pts (xy 120.65 187.96) (xy 123.19 187.96))
    (stroke (width 0) (type default))
  )
  (wire (pts (xy 292.1 170.18) (xy 290.83 170.18))
    (stroke (width 0) (type default))
  )
  (wire (pts (xy 237.49 121.92) (xy 250.19 121.92))
    (stroke (width 0) (type default))
  )
  (wire (pts (xy 279.4 83.82) (xy 279.4 85.09))
    (stroke (width 0) (type default))
  )
  (wire (pts (xy 100.33 242.57) (xy 97.79 242.57))
    (stroke (width 0) (type default))
  )
  (wire (pts (xy 135.89 67.31) (xy 135.89 68.58))
    (stroke (width 0) (type default))
  )
  (wire (pts (xy 344.17 173.99) (xy 344.17 180.34))
    (stroke (width 0) (type default))
  )
  (wire (pts (xy 386.08 30.48) (xy 394.97 30.48))
    (stroke (width 0) (type default))
  )
  (wire (pts (xy 120.65 177.8) (xy 123.19 177.8))
    (stroke (width 0) (type default))
  )
  (wire (pts (xy 100.33 193.04) (xy 97.79 193.04))
    (stroke (width 0) (type default))
  )
  (wire (pts (xy 358.14 229.87) (xy 355.6 229.87))
    (stroke (width 0) (type default))
  )
  (wire (pts (xy 289.56 52.07) (xy 298.45 52.07))
    (stroke (width 0) (type default))
  )
  (wire (pts (xy 375.92 69.85) (xy 370.84 69.85))
    (stroke (width 0) (type default))
  )
  (wire (pts (xy 115.57 26.67) (xy 115.57 29.21))
    (stroke (width 0) (type default))
  )
  (wire (pts (xy 323.85 227.33) (xy 322.58 227.33))
    (stroke (width 0) (type default))
  )
  (wire (pts (xy 194.31 130.81) (xy 196.85 130.81))
    (stroke (width 0) (type default))
  )
  (wire (pts (xy 160.02 233.68) (xy 160.02 260.35))
    (stroke (width 0) (type default))
  )
  (wire (pts (xy 325.12 39.37) (xy 325.12 43.18))
    (stroke (width 0) (type default))
  )
  (wire (pts (xy 323.85 119.38) (xy 323.85 116.84))
    (stroke (width 0) (type default))
  )
  (wire (pts (xy 194.31 130.81) (xy 194.31 134.62))
    (stroke (width 0) (type default))
  )
  (wire (pts (xy 50.8 219.71) (xy 58.42 219.71))
    (stroke (width 0) (type default))
  )
  (wire (pts (xy 123.19 26.67) (xy 132.08 26.67))
    (stroke (width 0) (type default))
  )
  (wire (pts (xy 370.84 44.45) (xy 386.08 44.45))
    (stroke (width 0) (type default))
  )
  (wire (pts (xy 143.51 107.95) (xy 142.24 107.95))
    (stroke (width 0) (type default))
  )
  (wire (pts (xy 68.58 176.53) (xy 68.58 199.39))
    (stroke (width 0) (type default))
  )
  (wire (pts (xy 331.47 39.37) (xy 331.47 44.45))
    (stroke (width 0) (type default))
  )
  (wire (pts (xy 369.57 168.91) (xy 374.65 168.91))
    (stroke (width 0) (type default))
  )
  (wire (pts (xy 224.79 224.79) (xy 231.14 224.79))
    (stroke (width 0) (type default))
  )
  (wire (pts (xy 358.14 224.79) (xy 355.6 224.79))
    (stroke (width 0) (type default))
  )
  (wire (pts (xy 76.2 185.42) (xy 76.2 207.01))
    (stroke (width 0) (type default))
  )
  (wire (pts (xy 148.59 179.07) (xy 146.05 179.07))
    (stroke (width 0) (type default))
  )
  (wire (pts (xy 266.7 162.56) (xy 266.7 165.1))
    (stroke (width 0) (type default))
  )
  (wire (pts (xy 331.47 116.84) (xy 337.82 116.84))
    (stroke (width 0) (type default))
  )
  (wire (pts (xy 100.33 195.58) (xy 97.79 195.58))
    (stroke (width 0) (type default))
  )
  (wire (pts (xy 121.92 201.93) (xy 121.92 204.47))
    (stroke (width 0) (type default))
  )
  (wire (pts (xy 153.67 29.21) (xy 153.67 31.75))
    (stroke (width 0) (type default))
  )
  (wire (pts (xy 251.46 248.92) (xy 255.27 248.92))
    (stroke (width 0) (type default))
  )
  (wire (pts (xy 151.13 228.6) (xy 151.13 220.98))
    (stroke (width 0) (type default))
  )
  (wire (pts (xy 143.51 60.96) (xy 143.51 62.23))
    (stroke (width 0) (type default))
  )
  (wire (pts (xy 53.34 261.62) (xy 53.34 267.97))
    (stroke (width 0) (type default))
  )
  (wire (pts (xy 168.91 52.07) (xy 196.85 52.07))
    (stroke (width 0) (type default))
  )
  (wire (pts (xy 374.65 151.13) (xy 369.57 151.13))
    (stroke (width 0) (type default))
  )
  (wire (pts (xy 307.34 48.26) (xy 307.34 52.07))
    (stroke (width 0) (type default))
  )
  (wire (pts (xy 143.51 67.31) (xy 143.51 68.58))
    (stroke (width 0) (type default))
  )
  (wire (pts (xy 63.5 167.64) (xy 66.04 167.64))
    (stroke (width 0) (type default))
  )
  (wire (pts (xy 375.92 222.25) (xy 393.7 222.25))
    (stroke (width 0) (type default))
  )
  (wire (pts (xy 81.28 251.46) (xy 81.28 252.73))
    (stroke (width 0) (type default))
  )
  (wire (pts (xy 388.62 125.73) (xy 397.51 125.73))
    (stroke (width 0) (type default))
  )
  (wire (pts (xy 295.91 81.28) (xy 297.18 81.28))
    (stroke (width 0) (type default))
  )
  (wire (pts (xy 370.84 74.93) (xy 375.92 74.93))
    (stroke (width 0) (type default))
  )
  (wire (pts (xy 58.42 229.87) (xy 67.31 229.87))
    (stroke (width 0) (type default))
  )
  (wire (pts (xy 375.92 57.15) (xy 370.84 57.15))
    (stroke (width 0) (type default))
  )
  (wire (pts (xy 71.12 167.64) (xy 71.12 180.34))
    (stroke (width 0) (type default))
  )
  (wire (pts (xy 105.41 26.67) (xy 115.57 26.67))
    (stroke (width 0) (type default))
  )
  (wire (pts (xy 176.53 22.86) (xy 182.88 22.86))
    (stroke (width 0) (type default))
  )
  (wire (pts (xy 243.84 270.51) (xy 246.38 270.51))
    (stroke (width 0) (type default))
  )
  (wire (pts (xy 43.18 219.71) (xy 50.8 219.71))
    (stroke (width 0) (type default))
  )
  (wire (pts (xy 396.24 45.72) (xy 396.24 46.99))
    (stroke (width 0) (type default))
  )
  (wire (pts (xy 76.2 229.87) (xy 76.2 231.14))
    (stroke (width 0) (type default))
  )
  (wire (pts (xy 73.66 48.26) (xy 73.66 49.53))
    (stroke (width 0) (type default))
  )
  (wire (pts (xy 138.43 247.65) (xy 173.99 247.65))
    (stroke (width 0) (type default))
  )
  (wire (pts (xy 394.97 29.21) (xy 394.97 30.48))
    (stroke (width 0) (type default))
  )
  (wire (pts (xy 40.64 273.05) (xy 40.64 276.86))
    (stroke (width 0) (type default))
  )
  (wire (pts (xy 342.9 171.45) (xy 345.44 171.45))
    (stroke (width 0) (type default))
  )
  (wire (pts (xy 194.31 45.72) (xy 196.85 45.72))
    (stroke (width 0) (type default))
  )
  (wire (pts (xy 394.97 36.83) (xy 394.97 38.1))
    (stroke (width 0) (type default))
  )
  (wire (pts (xy 355.6 232.41) (xy 355.6 234.95))
    (stroke (width 0) (type default))
  )
  (wire (pts (xy 60.96 191.77) (xy 55.88 191.77))
    (stroke (width 0) (type default))
  )
  (wire (pts (xy 160.02 220.98) (xy 165.1 220.98))
    (stroke (width 0) (type default))
  )
  (wire (pts (xy 289.56 39.37) (xy 289.56 43.18))
    (stroke (width 0) (type default))
  )
  (wire (pts (xy 72.39 273.05) (xy 72.39 276.86))
    (stroke (width 0) (type default))
  )
  (wire (pts (xy 261.62 248.92) (xy 260.35 248.92))
    (stroke (width 0) (type default))
  )
  (wire (pts (xy 194.31 64.77) (xy 196.85 64.77))
    (stroke (width 0) (type default))
  )
  (wire (pts (xy 147.32 252.73) (xy 173.99 252.73))
    (stroke (width 0) (type default))
  )
  (wire (pts (xy 224.79 224.79) (xy 224.79 227.33))
    (stroke (width 0) (type default))
  )
  (wire (pts (xy 388.62 118.11) (xy 397.51 118.11))
    (stroke (width 0) (type default))
  )
  (wire (pts (xy 60.96 167.64) (xy 63.5 167.64))
    (stroke (width 0) (type default))
  )
  (wire (pts (xy 142.24 107.95) (xy 142.24 105.41))
    (stroke (width 0) (type default))
  )
  (wire (pts (xy 91.44 162.56) (xy 91.44 161.29))
    (stroke (width 0) (type default))
  )
  (wire (pts (xy 135.89 60.96) (xy 135.89 62.23))
    (stroke (width 0) (type default))
  )
  (wire (pts (xy 182.88 39.37) (xy 194.31 39.37))
    (stroke (width 0) (type default))
  )
  (wire (pts (xy 234.95 262.89) (xy 234.95 261.62))
    (stroke (width 0) (type default))
  )
  (wire (pts (xy 261.62 270.51) (xy 260.35 270.51))
    (stroke (width 0) (type default))
  )
  (wire (pts (xy 397.51 140.97) (xy 397.51 142.24))
    (stroke (width 0) (type default))
  )
  (wire (pts (xy 50.8 229.87) (xy 58.42 229.87))
    (stroke (width 0) (type default))
  )
  (wire (pts (xy 374.65 138.43) (xy 369.57 138.43))
    (stroke (width 0) (type default))
  )
  (wire (pts (xy 290.83 167.64) (xy 292.1 167.64))
    (stroke (width 0) (type default))
  )
  (wire (pts (xy 194.31 54.61) (xy 194.31 45.72))
    (stroke (width 0) (type default))
  )
  (wire (pts (xy 66.04 185.42) (xy 66.04 196.85))
    (stroke (width 0) (type default))
  )
  (wire (pts (xy 369.57 133.35) (xy 388.62 133.35))
    (stroke (width 0) (type default))
  )
  (wire (pts (xy 160.02 228.6) (xy 160.02 220.98))
    (stroke (width 0) (type default))
  )
  (wire (pts (xy 138.43 220.98) (xy 142.24 220.98))
    (stroke (width 0) (type default))
  )
  (wire (pts (xy 375.92 64.77) (xy 370.84 64.77))
    (stroke (width 0) (type default))
  )
  (wire (pts (xy 55.88 196.85) (xy 66.04 196.85))
    (stroke (width 0) (type default))
  )
  (wire (pts (xy 234.95 261.62) (xy 231.14 261.62))
    (stroke (width 0) (type default))
  )
  (wire (pts (xy 58.42 167.64) (xy 58.42 171.45))
    (stroke (width 0) (type default))
  )
  (wire (pts (xy 142.24 45.72) (xy 194.31 45.72))
    (stroke (width 0) (type default))
  )
  (wire (pts (xy 375.92 54.61) (xy 370.84 54.61))
    (stroke (width 0) (type default))
  )
  (wire (pts (xy 358.14 234.95) (xy 355.6 234.95))
    (stroke (width 0) (type default))
  )
  (wire (pts (xy 187.96 116.84) (xy 182.88 116.84))
    (stroke (width 0) (type default))
  )
  (wire (pts (xy 375.92 237.49) (xy 375.92 222.25))
    (stroke (width 0) (type default))
  )
  (wire (pts (xy 182.88 116.84) (xy 182.88 120.65))
    (stroke (width 0) (type default))
  )
  (wire (pts (xy 403.86 30.48) (xy 403.86 31.75))
    (stroke (width 0) (type default))
  )
  (wire (pts (xy 129.54 97.79) (xy 129.54 105.41))
    (stroke (width 0) (type default))
  )
  (wire (pts (xy 388.62 229.87) (xy 393.7 229.87))
    (stroke (width 0) (type default))
  )
  (wire (pts (xy 289.56 167.64) (xy 290.83 167.64))
    (stroke (width 0) (type default))
  )
  (wire (pts (xy 96.52 262.89) (xy 96.52 265.43))
    (stroke (width 0) (type default))
  )
  (wire (pts (xy 156.21 60.96) (xy 168.91 60.96))
    (stroke (width 0) (type default))
  )
  (wire (pts (xy 142.24 110.49) (xy 142.24 113.03))
    (stroke (width 0) (type default))
  )
  (wire (pts (xy 193.04 116.84) (xy 196.85 116.84))
    (stroke (width 0) (type default))
  )
  (wire (pts (xy 403.86 38.1) (xy 403.86 39.37))
    (stroke (width 0) (type default))
  )
  (wire (pts (xy 355.6 219.71) (xy 355.6 222.25))
    (stroke (width 0) (type default))
  )
  (wire (pts (xy 295.91 83.82) (xy 295.91 81.28))
    (stroke (width 0) (type default))
  )
  (wire (pts (xy 335.28 171.45) (xy 337.82 171.45))
    (stroke (width 0) (type default))
  )
  (wire (pts (xy 397.51 124.46) (xy 397.51 125.73))
    (stroke (width 0) (type default))
  )
  (wire (pts (xy 386.08 237.49) (xy 386.08 227.33))
    (stroke (width 0) (type default))
  )
  (wire (pts (xy 325.12 48.26) (xy 325.12 52.07))
    (stroke (width 0) (type default))
  )
  (wire (pts (xy 226.06 248.92) (xy 231.14 248.92))
    (stroke (width 0) (type default))
  )
  (wire (pts (xy 374.65 140.97) (xy 369.57 140.97))
    (stroke (width 0) (type default))
  )
  (wire (pts (xy 323.85 129.54) (xy 331.47 129.54))
    (stroke (width 0) (type default))
  )
  (wire (pts (xy 314.96 129.54) (xy 323.85 129.54))
    (stroke (width 0) (type default))
  )
  (wire (pts (xy 307.34 52.07) (xy 316.23 52.07))
    (stroke (width 0) (type default))
  )
  (wire (pts (xy 194.31 39.37) (xy 196.85 39.37))
    (stroke (width 0) (type default))
  )
  (wire (pts (xy 298.45 116.84) (xy 294.64 116.84))
    (stroke (width 0) (type default))
  )
  (wire (pts (xy 396.24 46.99) (xy 405.13 46.99))
    (stroke (width 0) (type default))
  )
  (wire (pts (xy 120.65 242.57) (xy 129.54 242.57))
    (stroke (width 0) (type default))
  )
  (wire (pts (xy 388.62 116.84) (xy 388.62 118.11))
    (stroke (width 0) (type default))
  )
  (wire (pts (xy 156.21 257.81) (xy 173.99 257.81))
    (stroke (width 0) (type default))
  )
  (wire (pts (xy 58.42 219.71) (xy 67.31 219.71))
    (stroke (width 0) (type default))
  )
  (wire (pts (xy 370.84 77.47) (xy 375.92 77.47))
    (stroke (width 0) (type default))
  )
  (wire (pts (xy 331.47 124.46) (xy 331.47 129.54))
    (stroke (width 0) (type default))
  )
  (wire (pts (xy 196.85 128.27) (xy 194.31 128.27))
    (stroke (width 0) (type default))
  )
  (wire (pts (xy 298.45 39.37) (xy 307.34 39.37))
    (stroke (width 0) (type default))
  )
  (wire (pts (xy 58.42 222.25) (xy 58.42 219.71))
    (stroke (width 0) (type default))
  )
  (wire (pts (xy 60.96 185.42) (xy 60.96 191.77))
    (stroke (width 0) (type default))
  )
  (wire (pts (xy 172.72 64.77) (xy 172.72 68.58))
    (stroke (width 0) (type default))
  )
  (wire (pts (xy 151.13 233.68) (xy 151.13 255.27))
    (stroke (width 0) (type default))
  )
  (wire (pts (xy 134.62 111.76) (xy 134.62 113.03))
    (stroke (width 0) (type default))
  )
  (wire (pts (xy 340.36 140.97) (xy 345.44 140.97))
    (stroke (width 0) (type default))
  )
  (wire (pts (xy 129.54 228.6) (xy 129.54 220.98))
    (stroke (width 0) (type default))
  )
  (wire (pts (xy 172.72 76.2) (xy 196.85 76.2))
    (stroke (width 0) (type default))
  )
  (wire (pts (xy 66.04 267.97) (xy 66.04 261.62))
    (stroke (width 0) (type default))
  )
  (wire (pts (xy 72.39 261.62) (xy 72.39 267.97))
    (stroke (width 0) (type default))
  )
  (wire (pts (xy 156.21 220.98) (xy 156.21 228.6))
    (stroke (width 0) (type default))
  )
  (wire (pts (xy 76.2 207.01) (xy 55.88 207.01))
    (stroke (width 0) (type default))
  )
  (wire (pts (xy 165.1 233.68) (xy 165.1 262.89))
    (stroke (width 0) (type default))
  )
  (wire (pts (xy 168.91 22.86) (xy 176.53 22.86))
    (stroke (width 0) (type default))
  )
  (wire (pts (xy 196.85 54.61) (xy 194.31 54.61))
    (stroke (width 0) (type default))
  )
  (wire (pts (xy 398.78 238.76) (xy 398.78 236.22))
    (stroke (width 0) (type default))
  )
  (wire (pts (xy 226.06 248.92) (xy 226.06 251.46))
    (stroke (width 0) (type default))
  )
  (wire (pts (xy 138.43 228.6) (xy 138.43 220.98))
    (stroke (width 0) (type default))
  )
  (wire (pts (xy 322.58 222.25) (xy 323.85 222.25))
    (stroke (width 0) (type default))
  )
  (wire (pts (xy 165.1 228.6) (xy 165.1 220.98))
    (stroke (width 0) (type default))
  )
  (wire (pts (xy 386.08 44.45) (xy 386.08 30.48))
    (stroke (width 0) (type default))
  )
  (wire (pts (xy 129.54 242.57) (xy 173.99 242.57))
    (stroke (width 0) (type default))
  )
  (wire (pts (xy 120.65 257.81) (xy 156.21 257.81))
    (stroke (width 0) (type default))
  )
  (wire (pts (xy 250.19 121.92) (xy 250.19 124.46))
    (stroke (width 0) (type default))
  )
  (wire (pts (xy 67.31 229.87) (xy 76.2 229.87))
    (stroke (width 0) (type default))
  )
  (wire (pts (xy 46.99 273.05) (xy 46.99 276.86))
    (stroke (width 0) (type default))
  )
  (wire (pts (xy 346.71 81.28) (xy 334.01 81.28))
    (stroke (width 0) (type default))
  )
  (wire (pts (xy 67.31 222.25) (xy 67.31 219.71))
    (stroke (width 0) (type default))
  )
  (wire (pts (xy 298.45 129.54) (xy 306.07 129.54))
    (stroke (width 0) (type default))
  )
  (wire (pts (xy 196.85 41.91) (xy 194.31 41.91))
    (stroke (width 0) (type default))
  )
  (wire (pts (xy 327.66 62.23) (xy 335.28 62.23))
    (stroke (width 0) (type default))
  )
  (wire (pts (xy 340.36 62.23) (xy 346.71 62.23))
    (stroke (width 0) (type default))
  )
  (wire (pts (xy 368.3 224.79) (xy 378.46 224.79))
    (stroke (width 0) (type default))
  )
  (wire (pts (xy 323.85 124.46) (xy 323.85 129.54))
    (stroke (width 0) (type default))
  )
  (wire (pts (xy 279.4 77.47) (xy 279.4 78.74))
    (stroke (width 0) (type default))
  )
  (wire (pts (xy 340.36 133.35) (xy 345.44 133.35))
    (stroke (width 0) (type default))
  )
  (wire (pts (xy 76.2 219.71) (xy 81.28 219.71))
    (stroke (width 0) (type default))
  )
  (wire (pts (xy 45.72 39.37) (xy 40.64 39.37))
    (stroke (width 0) (type default))
  )
  (wire (pts (xy 165.1 262.89) (xy 173.99 262.89))
    (stroke (width 0) (type default))
  )
  (wire (pts (xy 50.8 229.87) (xy 43.18 229.87))
    (stroke (width 0) (type default))
  )
  (wire (pts (xy 123.19 170.18) (xy 120.65 170.18))
    (stroke (width 0) (type default))
  )
  (wire (pts (xy 166.37 67.31) (xy 163.83 67.31))
    (stroke (width 0) (type default))
  )
  (wire (pts (xy 40.64 267.97) (xy 40.64 261.62))
    (stroke (width 0) (type default))
  )
  (wire (pts (xy 331.47 116.84) (xy 331.47 119.38))
    (stroke (width 0) (type default))
  )
  (wire (pts (xy 370.84 85.09) (xy 375.92 85.09))
    (stroke (width 0) (type default))
  )
  (wire (pts (xy 127 46.99) (xy 137.16 46.99))
    (stroke (width 0) (type default))
  )
  (wire (pts (xy 71.12 201.93) (xy 55.88 201.93))
    (stroke (width 0) (type default))
  )
  (wire (pts (xy 388.62 118.11) (xy 388.62 119.38))
    (stroke (width 0) (type default))
  )
  (wire (pts (xy 289.56 39.37) (xy 287.02 39.37))
    (stroke (width 0) (type default))
  )
  (wire (pts (xy 50.8 227.33) (xy 50.8 229.87))
    (stroke (width 0) (type default))
  )
  (wire (pts (xy 251.46 270.51) (xy 255.27 270.51))
    (stroke (width 0) (type default))
  )
  (wire (pts (xy 129.54 105.41) (xy 134.62 105.41))
    (stroke (width 0) (type default))
  )
  (wire (pts (xy 137.16 45.72) (xy 137.16 46.99))
    (stroke (width 0) (type default))
  )
  (wire (pts (xy 166.37 73.66) (xy 166.37 76.2))
    (stroke (width 0) (type default))
  )
  (wire (pts (xy 194.31 41.91) (xy 194.31 39.37))
    (stroke (width 0) (type default))
  )
  (wire (pts (xy 113.03 60.96) (xy 121.92 60.96))
    (stroke (width 0) (type default))
  )
  (wire (pts (xy 405.13 53.34) (xy 405.13 55.88))
    (stroke (width 0) (type default))
  )
  (wire (pts (xy 100.33 180.34) (xy 97.79 180.34))
    (stroke (width 0) (type default))
  )
  (wire (pts (xy 226.06 270.51) (xy 231.14 270.51))
    (stroke (width 0) (type default))
  )
  (wire (pts (xy 250.19 118.11) (xy 250.19 121.92))
    (stroke (width 0) (type default))
  )
  (wire (pts (xy 68.58 167.64) (xy 68.58 171.45))
    (stroke (width 0) (type default))
  )
  (wire (pts (xy 166.37 67.31) (xy 166.37 68.58))
    (stroke (width 0) (type default))
  )
  (wire (pts (xy 133.35 220.98) (xy 138.43 220.98))
    (stroke (width 0) (type default))
  )
  (wire (pts (xy 341.63 46.99) (xy 346.71 46.99))
    (stroke (width 0) (type default))
  )
  (wire (pts (xy 234.95 217.17) (xy 234.95 215.9))
    (stroke (width 0) (type default))
  )
  (wire (pts (xy 120.65 190.5) (xy 123.19 190.5))
    (stroke (width 0) (type default))
  )
  (wire (pts (xy 45.72 52.07) (xy 45.72 53.34))
    (stroke (width 0) (type default))
  )
  (wire (pts (xy 378.46 224.79) (xy 393.7 224.79))
    (stroke (width 0) (type default))
  )
  (wire (pts (xy 120.65 265.43) (xy 168.91 265.43))
    (stroke (width 0) (type default))
  )
  (wire (pts (xy 97.79 161.29) (xy 91.44 161.29))
    (stroke (width 0) (type default))
  )
  (wire (pts (xy 127 60.96) (xy 135.89 60.96))
    (stroke (width 0) (type default))
  )
  (wire (pts (xy 316.23 81.28) (xy 326.39 81.28))
    (stroke (width 0) (type default))
  )
  (wire (pts (xy 120.65 240.03) (xy 123.19 240.03))
    (stroke (width 0) (type default))
  )
  (wire (pts (xy 67.31 43.18) (xy 67.31 39.37))
    (stroke (width 0) (type default))
  )
  (wire (pts (xy 40.64 44.45) (xy 44.45 44.45))
    (stroke (width 0) (type default))
  )
  (wire (pts (xy 237.49 44.45) (xy 250.19 44.45))
    (stroke (width 0) (type default))
  )
  (wire (pts (xy 73.66 167.64) (xy 73.66 171.45))
    (stroke (width 0) (type default))
  )
  (wire (pts (xy 142.24 105.41) (xy 143.51 105.41))
    (stroke (width 0) (type default))
  )
  (wire (pts (xy 163.83 64.77) (xy 172.72 64.77))
    (stroke (width 0) (type default))
  )
  (wire (pts (xy 59.69 261.62) (xy 59.69 267.97))
    (stroke (width 0) (type default))
  )
  (wire (pts (xy 168.91 60.96) (xy 168.91 52.07))
    (stroke (width 0) (type default))
  )
  (wire (pts (xy 100.33 262.89) (xy 96.52 262.89))
    (stroke (width 0) (type default))
  )
  (wire (pts (xy 60.96 167.64) (xy 60.96 180.34))
    (stroke (width 0) (type default))
  )
  (wire (pts (xy 168.91 265.43) (xy 173.99 265.43))
    (stroke (width 0) (type default))
  )
  (wire (pts (xy 76.2 219.71) (xy 76.2 222.25))
    (stroke (width 0) (type default))
  )
  (wire (pts (xy 370.84 82.55) (xy 375.92 82.55))
    (stroke (width 0) (type default))
  )
  (wire (pts (xy 388.62 132.08) (xy 388.62 133.35))
    (stroke (width 0) (type default))
  )
  (wire (pts (xy 46.99 261.62) (xy 40.64 261.62))
    (stroke (width 0) (type default))
  )
  (wire (pts (xy 45.72 31.75) (xy 40.64 31.75))
    (stroke (width 0) (type default))
  )
  (wire (pts (xy 100.33 177.8) (xy 97.79 177.8))
    (stroke (width 0) (type default))
  )
  (wire (pts (xy 394.97 30.48) (xy 403.86 30.48))
    (stroke (width 0) (type default))
  )
  (wire (pts (xy 306.07 116.84) (xy 314.96 116.84))
    (stroke (width 0) (type default))
  )
  (wire (pts (xy 137.16 53.34) (xy 137.16 54.61))
    (stroke (width 0) (type default))
  )
  (wire (pts (xy 377.19 118.11) (xy 388.62 118.11))
    (stroke (width 0) (type default))
  )
  (wire (pts (xy 168.91 220.98) (xy 168.91 228.6))
    (stroke (width 0) (type default))
  )
  (wire (pts (xy 345.44 87.63) (xy 345.44 91.44))
    (stroke (width 0) (type default))
  )
  (wire (pts (xy 66.04 261.62) (xy 72.39 261.62))
    (stroke (width 0) (type default))
  )
  (wire (pts (xy 250.19 129.54) (xy 250.19 132.08))
    (stroke (width 0) (type default))
  )
  (wire (pts (xy 369.57 163.83) (xy 374.65 163.83))
    (stroke (width 0) (type default))
  )
  (wire (pts (xy 369.57 130.81) (xy 377.19 130.81))
    (stroke (width 0) (type default))
  )
  (wire (pts (xy 374.65 143.51) (xy 369.57 143.51))
    (stroke (width 0) (type default))
  )
  (wire (pts (xy 374.65 156.21) (xy 369.57 156.21))
    (stroke (width 0) (type default))
  )
  (wire (pts (xy 298.45 124.46) (xy 298.45 129.54))
    (stroke (width 0) (type default))
  )
  (wire (pts (xy 358.14 227.33) (xy 355.6 227.33))
    (stroke (width 0) (type default))
  )
  (wire (pts (xy 63.5 167.64) (xy 63.5 171.45))
    (stroke (width 0) (type default))
  )
  (wire (pts (xy 59.69 261.62) (xy 66.04 261.62))
    (stroke (width 0) (type default))
  )
  (wire (pts (xy 135.89 60.96) (xy 143.51 60.96))
    (stroke (width 0) (type default))
  )
  (wire (pts (xy 306.07 119.38) (xy 306.07 116.84))
    (stroke (width 0) (type default))
  )
  (wire (pts (xy 120.65 262.89) (xy 165.1 262.89))
    (stroke (width 0) (type default))
  )
  (wire (pts (xy 298.45 129.54) (xy 298.45 130.81))
    (stroke (width 0) (type default))
  )
  (wire (pts (xy 115.57 26.67) (xy 123.19 26.67))
    (stroke (width 0) (type default))
  )
  (wire (pts (xy 46.99 276.86) (xy 53.34 276.86))
    (stroke (width 0) (type default))
  )
  (wire (pts (xy 386.08 227.33) (xy 393.7 227.33))
    (stroke (width 0) (type default))
  )
  (wire (pts (xy 40.64 49.53) (xy 45.72 49.53))
    (stroke (width 0) (type default))
  )
  (wire (pts (xy 237.49 41.91) (xy 250.19 41.91))
    (stroke (width 0) (type default))
  )
  (wire (pts (xy 74.93 245.11) (xy 74.93 246.38))
    (stroke (width 0) (type default))
  )
  (wire (pts (xy 133.35 228.6) (xy 133.35 220.98))
    (stroke (width 0) (type default))
  )
  (wire (pts (xy 120.65 193.04) (xy 123.19 193.04))
    (stroke (width 0) (type default))
  )
  (wire (pts (xy 378.46 237.49) (xy 378.46 224.79))
    (stroke (width 0) (type default))
  )
  (wire (pts (xy 388.62 133.35) (xy 397.51 133.35))
    (stroke (width 0) (type default))
  )
  (wire (pts (xy 66.04 167.64) (xy 66.04 180.34))
    (stroke (width 0) (type default))
  )
  (wire (pts (xy 355.6 227.33) (xy 355.6 229.87))
    (stroke (width 0) (type default))
  )
  (wire (pts (xy 290.83 170.18) (xy 290.83 167.64))
    (stroke (width 0) (type default))
  )
  (wire (pts (xy 182.88 93.98) (xy 196.85 93.98))
    (stroke (width 0) (type default))
  )
  (wire (pts (xy 59.69 273.05) (xy 59.69 276.86))
    (stroke (width 0) (type default))
  )
  (wire (pts (xy 298.45 39.37) (xy 298.45 43.18))
    (stroke (width 0) (type default))
  )
  (wire (pts (xy 289.56 53.34) (xy 289.56 52.07))
    (stroke (width 0) (type default))
  )
  (wire (pts (xy 369.57 166.37) (xy 374.65 166.37))
    (stroke (width 0) (type default))
  )
  (wire (pts (xy 237.49 127) (xy 238.76 127))
    (stroke (width 0) (type default))
  )
  (wire (pts (xy 123.19 26.67) (xy 123.19 29.21))
    (stroke (width 0) (type default))
  )
  (wire (pts (xy 295.91 86.36) (xy 295.91 87.63))
    (stroke (width 0) (type default))
  )
  (wire (pts (xy 120.65 245.11) (xy 133.35 245.11))
    (stroke (width 0) (type default))
  )
  (wire (pts (xy 120.65 250.19) (xy 142.24 250.19))
    (stroke (width 0) (type default))
  )
  (wire (pts (xy 250.19 107.95) (xy 250.19 113.03))
    (stroke (width 0) (type default))
  )
  (wire (pts (xy 368.3 229.87) (xy 388.62 229.87))
    (stroke (width 0) (type default))
  )
  (wire (pts (xy 345.44 167.64) (xy 332.74 167.64))
    (stroke (width 0) (type default))
  )
  (wire (pts (xy 165.1 220.98) (xy 168.91 220.98))
    (stroke (width 0) (type default))
  )
  (wire (pts (xy 316.23 52.07) (xy 325.12 52.07))
    (stroke (width 0) (type default))
  )
  (wire (pts (xy 142.24 250.19) (xy 173.99 250.19))
    (stroke (width 0) (type default))
  )
  (wire (pts (xy 397.51 139.7) (xy 397.51 140.97))
    (stroke (width 0) (type default))
  )
  (wire (pts (xy 100.33 172.72) (xy 97.79 172.72))
    (stroke (width 0) (type default))
  )
  (wire (pts (xy 311.15 167.64) (xy 323.85 167.64))
    (stroke (width 0) (type default))
  )
  (wire (pts (xy 341.63 52.07) (xy 346.71 52.07))
    (stroke (width 0) (type default))
  )
  (wire (pts (xy 53.34 276.86) (xy 59.69 276.86))
    (stroke (width 0) (type default))
  )
  (wire (pts (xy 234.95 238.76) (xy 231.14 238.76))
    (stroke (width 0) (type default))
  )
  (wire (pts (xy 331.47 44.45) (xy 346.71 44.45))
    (stroke (width 0) (type default))
  )
  (wire (pts (xy 182.88 22.86) (xy 182.88 39.37))
    (stroke (width 0) (type default))
  )
  (wire (pts (xy 48.26 167.64) (xy 58.42 167.64))
    (stroke (width 0) (type default))
  )
  (wire (pts (xy 251.46 224.79) (xy 255.27 224.79))
    (stroke (width 0) (type default))
  )
  (wire (pts (xy 161.29 22.86) (xy 161.29 24.13))
    (stroke (width 0) (type default))
  )
  (wire (pts (xy 73.66 43.18) (xy 73.66 39.37))
    (stroke (width 0) (type default))
  )
  (wire (pts (xy 100.33 185.42) (xy 97.79 185.42))
    (stroke (width 0) (type default))
  )
  (wire (pts (xy 337.82 130.81) (xy 337.82 116.84))
    (stroke (width 0) (type default))
  )
  (wire (pts (xy 316.23 48.26) (xy 316.23 52.07))
    (stroke (width 0) (type default))
  )
  (wire (pts (xy 194.31 62.23) (xy 196.85 62.23))
    (stroke (width 0) (type default))
  )
  (wire (pts (xy 323.85 116.84) (xy 331.47 116.84))
    (stroke (width 0) (type default))
  )
  (wire (pts (xy 68.58 167.64) (xy 71.12 167.64))
    (stroke (width 0) (type default))
  )
  (wire (pts (xy 368.3 222.25) (xy 375.92 222.25))
    (stroke (width 0) (type default))
  )
  (wire (pts (xy 91.44 167.64) (xy 91.44 168.91))
    (stroke (width 0) (type default))
  )
  (wire (pts (xy 340.36 138.43) (xy 345.44 138.43))
    (stroke (width 0) (type default))
  )
  (wire (pts (xy 370.84 80.01) (xy 375.92 80.01))
    (stroke (width 0) (type default))
  )
  (wire (pts (xy 261.62 224.79) (xy 260.35 224.79))
    (stroke (width 0) (type default))
  )
  (wire (pts (xy 355.6 222.25) (xy 355.6 224.79))
    (stroke (width 0) (type default))
  )
  (wire (pts (xy 314.96 124.46) (xy 314.96 129.54))
    (stroke (width 0) (type default))
  )
  (wire (pts (xy 388.62 124.46) (xy 388.62 125.73))
    (stroke (width 0) (type default))
  )
  (wire (pts (xy 388.62 140.97) (xy 397.51 140.97))
    (stroke (width 0) (type default))
  )
  (wire (pts (xy 58.42 167.64) (xy 60.96 167.64))
    (stroke (width 0) (type default))
  )
  (wire (pts (xy 120.65 252.73) (xy 147.32 252.73))
    (stroke (width 0) (type default))
  )
  (wire (pts (xy 142.24 220.98) (xy 142.24 228.6))
    (stroke (width 0) (type default))
  )
  (wire (pts (xy 147.32 233.68) (xy 147.32 252.73))
    (stroke (width 0) (type default))
  )
  (wire (pts (xy 397.51 118.11) (xy 397.51 119.38))
    (stroke (width 0) (type default))
  )
  (wire (pts (xy 243.84 224.79) (xy 246.38 224.79))
    (stroke (width 0) (type default))
  )
  (wire (pts (xy 355.6 234.95) (xy 355.6 240.03))
    (stroke (width 0) (type default))
  )
  (wire (pts (xy 176.53 22.86) (xy 176.53 24.13))
    (stroke (width 0) (type default))
  )
  (wire (pts (xy 120.65 260.35) (xy 160.02 260.35))
    (stroke (width 0) (type default))
  )
  (wire (pts (xy 342.9 148.59) (xy 345.44 148.59))
    (stroke (width 0) (type default))
  )
  (wire (pts (xy 147.32 228.6) (xy 147.32 220.98))
    (stroke (width 0) (type default))
  )
  (wire (pts (xy 96.52 265.43) (xy 100.33 265.43))
    (stroke (width 0) (type default))
  )
  (wire (pts (xy 45.72 49.53) (xy 45.72 52.07))
    (stroke (width 0) (type default))
  )
  (wire (pts (xy 50.8 222.25) (xy 50.8 219.71))
    (stroke (width 0) (type default))
  )
  (wire (pts (xy 237.49 39.37) (xy 250.19 39.37))
    (stroke (width 0) (type default))
  )
  (wire (pts (xy 335.28 148.59) (xy 337.82 148.59))
    (stroke (width 0) (type default))
  )
  (wire (pts (xy 375.92 59.69) (xy 370.84 59.69))
    (stroke (width 0) (type default))
  )
  (wire (pts (xy 81.28 240.03) (xy 97.79 240.03))
    (stroke (width 0) (type default))
  )
  (wire (pts (xy 43.18 222.25) (xy 43.18 219.71))
    (stroke (width 0) (type default))
  )
  (wire (pts (xy 138.43 233.68) (xy 138.43 247.65))
    (stroke (width 0) (type default))
  )
  (wire (pts (xy 128.27 240.03) (xy 173.99 240.03))
    (stroke (width 0) (type default))
  )
  (wire (pts (xy 403.86 36.83) (xy 403.86 38.1))
    (stroke (width 0) (type default))
  )
  (wire (pts (xy 133.35 245.11) (xy 173.99 245.11))
    (stroke (width 0) (type default))
  )
  (wire (pts (xy 73.66 167.64) (xy 76.2 167.64))
    (stroke (width 0) (type default))
  )
  (wire (pts (xy 168.91 220.98) (xy 173.99 220.98))
    (stroke (width 0) (type default))
  )
  (wire (pts (xy 369.57 171.45) (xy 374.65 171.45))
    (stroke (width 0) (type default))
  )
  (wire (pts (xy 73.66 204.47) (xy 55.88 204.47))
    (stroke (width 0) (type default))
  )
  (wire (pts (xy 95.25 252.73) (xy 100.33 252.73))
    (stroke (width 0) (type default))
  )
  (wire (pts (xy 147.32 46.99) (xy 147.32 49.53))
    (stroke (width 0) (type default))
  )
  (wire (pts (xy 374.65 146.05) (xy 369.57 146.05))
    (stroke (width 0) (type default))
  )
  (wire (pts (xy 172.72 76.2) (xy 172.72 73.66))
    (stroke (width 0) (type default))
  )
  (wire (pts (xy 142.24 233.68) (xy 142.24 250.19))
    (stroke (width 0) (type default))
  )
  (wire (pts (xy 146.05 179.07) (xy 146.05 184.15))
    (stroke (width 0) (type default))
  )
  (wire (pts (xy 374.65 148.59) (xy 369.57 148.59))
    (stroke (width 0) (type default))
  )
  (wire (pts (xy 59.69 261.62) (xy 53.34 261.62))
    (stroke (width 0) (type default))
  )
  (wire (pts (xy 322.58 224.79) (xy 323.85 224.79))
    (stroke (width 0) (type default))
  )
  (wire (pts (xy 120.65 195.58) (xy 123.19 195.58))
    (stroke (width 0) (type default))
  )
  (wire (pts (xy 322.58 217.17) (xy 323.85 217.17))
    (stroke (width 0) (type default))
  )
  (wire (pts (xy 297.18 86.36) (xy 295.91 86.36))
    (stroke (width 0) (type default))
  )
  (wire (pts (xy 66.04 167.64) (xy 68.58 167.64))
    (stroke (width 0) (type default))
  )
  (wire (pts (xy 67.31 219.71) (xy 76.2 219.71))
    (stroke (width 0) (type default))
  )
  (wire (pts (xy 142.24 220.98) (xy 147.32 220.98))
    (stroke (width 0) (type default))
  )

  (text "USER LEDs " (at 233.68 205.105 0)
    (effects (font (size 2.9972 2.9972) (thickness 0.5994) bold) (justify left bottom))
  )
  (text "USB Client" (at 344.805 116.205 0)
    (effects (font (size 2.9972 2.9972) (thickness 0.5994) bold) (justify left bottom))
  )
  (text "HPM SPI" (at 312.42 205.105 0)
    (effects (font (size 2.9972 2.9972) (thickness 0.5994) bold) (justify left bottom))
  )
  (text "JTAG/FTDI" (at 206.375 26.035 0)
    (effects (font (size 2.9972 2.9972) (thickness 0.5994) bold) (justify left bottom))
  )
  (text "Debug USB" (at 17.78 20.32 0)
    (effects (font (size 2.9972 2.9972) (thickness 0.5994) bold) (justify left bottom))
  )
  (text "JTAG connector" (at 360.68 205.105 0)
    (effects (font (size 2.9972 2.9972) (thickness 0.5994) bold) (justify left bottom))
  )
  (text "USB HOST" (at 346.71 27.305 0)
    (effects (font (size 2.9972 2.9972) (thickness 0.5994) bold) (justify left bottom))
  )
  (text "reserved for future use (as  of DC-SCI OPC specification)"
    (at 295.91 207.645 0)
    (effects (font (size 1.27 1.27)) (justify left bottom))
  )
  (text "I3C voltage level translation" (at 70.485 151.13 0)
    (effects (font (size 2.9972 2.9972) (thickness 0.5994) bold) (justify left bottom))
  )

  (label "USB2_CLK" (at 332.74 167.64 0) (fields_autoplaced)
    (effects (font (size 1.27 1.27)) (justify left bottom))
  )
  (label "USB1_CLK" (at 326.39 81.28 180) (fields_autoplaced)
    (effects (font (size 1.27 1.27)) (justify right bottom))
  )
  (label "USB2_CLK" (at 323.85 167.64 180) (fields_autoplaced)
    (effects (font (size 1.27 1.27)) (justify right bottom))
  )
  (label "FTDI_CLK" (at 182.88 93.98 0) (fields_autoplaced)
    (effects (font (size 1.27 1.27)) (justify left bottom))
  )
  (label "USB1_CLK" (at 334.01 81.28 0) (fields_autoplaced)
    (effects (font (size 1.27 1.27)) (justify left bottom))
  )
  (label "FTDI_CLK" (at 175.26 105.41 180) (fields_autoplaced)
    (effects (font (size 1.27 1.27)) (justify right bottom))
  )

  (global_label "I3C[3]_SDA_1V0" (shape input) (at 123.19 195.58 0) (fields_autoplaced)
    (effects (font (size 1.27 1.27)) (justify left))
    (property "Intersheetrefs" "${INTERSHEET_REFS}" (at -16.51 10.16 0)
      (effects (font (size 1.27 1.27)) hide)
    )
  )
  (global_label "I3C[2]_SCL_3V3" (shape input) (at 97.79 187.96 180) (fields_autoplaced)
    (effects (font (size 1.27 1.27)) (justify right))
    (property "Intersheetrefs" "${INTERSHEET_REFS}" (at -6.35 10.16 0)
      (effects (font (size 1.27 1.27)) hide)
    )
  )
  (global_label "I3C[2]_SDA_3V3" (shape input) (at 97.79 190.5 180) (fields_autoplaced)
    (effects (font (size 1.27 1.27)) (justify right))
    (property "Intersheetrefs" "${INTERSHEET_REFS}" (at -6.35 10.16 0)
      (effects (font (size 1.27 1.27)) hide)
    )
  )
  (global_label "VCC3V3" (shape input) (at 261.62 248.92 0) (fields_autoplaced)
    (effects (font (size 1.27 1.27)) (justify left))
    (property "Intersheetrefs" "${INTERSHEET_REFS}" (at 10.16 0.635 0)
      (effects (font (size 1.27 1.27)) hide)
    )
  )
  (global_label "VCC3V3" (shape input) (at 393.7 219.71 0) (fields_autoplaced)
    (effects (font (size 1.27 1.27)) (justify left))
    (property "Intersheetrefs" "${INTERSHEET_REFS}" (at 403.1672 219.71 0)
      (effects (font (size 1.27 1.27)) (justify left) hide)
    )
  )
  (global_label "JTAG_TDI" (shape input) (at 393.7 229.87 0) (fields_autoplaced)
    (effects (font (size 1.27 1.27)) (justify left))
    (property "Intersheetrefs" "${INTERSHEET_REFS}" (at 172.72 52.07 0)
      (effects (font (size 1.27 1.27)) hide)
    )
  )
  (global_label "USB1_DN" (shape input) (at 341.63 52.07 180) (fields_autoplaced)
    (effects (font (size 1.27 1.27)) (justify right))
    (property "Intersheetrefs" "${INTERSHEET_REFS}" (at 15.875 -6.985 0)
      (effects (font (size 1.27 1.27)) hide)
    )
  )
  (global_label "USR_LED0" (shape input) (at 229.87 215.9 180) (fields_autoplaced)
    (effects (font (size 1.27 1.27)) (justify right))
    (property "Intersheetrefs" "${INTERSHEET_REFS}" (at 12.7 0.635 0)
      (effects (font (size 1.27 1.27)) hide)
    )
  )
  (global_label "I3C[0]_SDA_1V0" (shape input) (at 123.19 180.34 0) (fields_autoplaced)
    (effects (font (size 1.27 1.27)) (justify left))
    (property "Intersheetrefs" "${INTERSHEET_REFS}" (at -16.51 10.16 0)
      (effects (font (size 1.27 1.27)) hide)
    )
  )
  (global_label "DBG_USB_D_P" (shape input) (at 45.72 36.83 0) (fields_autoplaced)
    (effects (font (size 1.27 1.27)) (justify left))
    (property "Intersheetrefs" "${INTERSHEET_REFS}" (at -23.495 -14.605 0)
      (effects (font (size 1.27 1.27)) hide)
    )
  )
  (global_label "VCC3V3" (shape input) (at 322.58 214.63 180) (fields_autoplaced)
    (effects (font (size 1.27 1.27)) (justify right))
    (property "Intersheetrefs" "${INTERSHEET_REFS}" (at 313.1128 214.63 0)
      (effects (font (size 1.27 1.27)) (justify right) hide)
    )
  )
  (global_label "I3C[1]_SCL_1V0" (shape input) (at 123.19 182.88 0) (fields_autoplaced)
    (effects (font (size 1.27 1.27)) (justify left))
    (property "Intersheetrefs" "${INTERSHEET_REFS}" (at -16.51 10.16 0)
      (effects (font (size 1.27 1.27)) hide)
    )
  )
  (global_label "I3C[1]_SDA_3V3" (shape input) (at 97.79 185.42 180) (fields_autoplaced)
    (effects (font (size 1.27 1.27)) (justify right))
    (property "Intersheetrefs" "${INTERSHEET_REFS}" (at -6.35 10.16 0)
      (effects (font (size 1.27 1.27)) hide)
    )
  )
  (global_label "ULPI1_CLKO" (shape input) (at 375.92 82.55 0) (fields_autoplaced)
    (effects (font (size 1.27 1.27)) (justify left))
    (property "Intersheetrefs" "${INTERSHEET_REFS}" (at -5.715 -8.255 0)
      (effects (font (size 1.27 1.27)) hide)
    )
  )
  (global_label "ULPI1_RESET" (shape input) (at 375.92 85.09 0) (fields_autoplaced)
    (effects (font (size 1.27 1.27)) (justify left))
    (property "Intersheetrefs" "${INTERSHEET_REFS}" (at -5.715 -8.255 0)
      (effects (font (size 1.27 1.27)) hide)
    )
  )
  (global_label "I3C[0]_SCL_3V3" (shape input) (at 97.79 177.8 180) (fields_autoplaced)
    (effects (font (size 1.27 1.27)) (justify right))
    (property "Intersheetrefs" "${INTERSHEET_REFS}" (at -6.35 10.16 0)
      (effects (font (size 1.27 1.27)) hide)
    )
  )
  (global_label "MMC_DAT1" (shape input) (at 173.99 250.19 0) (fields_autoplaced)
    (effects (font (size 1.27 1.27)) (justify left))
    (property "Intersheetrefs" "${INTERSHEET_REFS}" (at -3.81 -6.35 0)
      (effects (font (size 1.27 1.27)) hide)
    )
  )
  (global_label "ULPI2_NXT" (shape input) (at 374.65 161.29 0) (fields_autoplaced)
    (effects (font (size 1.27 1.27)) (justify left))
    (property "Intersheetrefs" "${INTERSHEET_REFS}" (at -6.35 -29.21 0)
      (effects (font (size 1.27 1.27)) hide)
    )
  )
  (global_label "I3C[2]_SDA_1V0" (shape input) (at 123.19 190.5 0) (fields_autoplaced)
    (effects (font (size 1.27 1.27)) (justify left))
    (property "Intersheetrefs" "${INTERSHEET_REFS}" (at -16.51 10.16 0)
      (effects (font (size 1.27 1.27)) hide)
    )
  )
  (global_label "VCC1V0" (shape input) (at 148.59 179.07 0) (fields_autoplaced)
    (effects (font (size 1.27 1.27)) (justify left))
    (property "Intersheetrefs" "${INTERSHEET_REFS}" (at 0.635 -10.16 0)
      (effects (font (size 1.27 1.27)) hide)
    )
  )
  (global_label "VCC3V3" (shape input) (at 144.78 22.86 180) (fields_autoplaced)
    (effects (font (size 1.27 1.27)) (justify right))
    (property "Intersheetrefs" "${INTERSHEET_REFS}" (at 115.57 176.53 0)
      (effects (font (size 1.27 1.27)) hide)
    )
  )
  (global_label "USR_LED2" (shape input) (at 231.14 261.62 180) (fields_autoplaced)
    (effects (font (size 1.27 1.27)) (justify right))
    (property "Intersheetrefs" "${INTERSHEET_REFS}" (at 13.335 0.635 0)
      (effects (font (size 1.27 1.27)) hide)
    )
  )
  (global_label "MMC_DAT0" (shape input) (at 173.99 247.65 0) (fields_autoplaced)
    (effects (font (size 1.27 1.27)) (justify left))
    (property "Intersheetrefs" "${INTERSHEET_REFS}" (at -3.81 -6.35 0)
      (effects (font (size 1.27 1.27)) hide)
    )
  )
  (global_label "ULPI2_STP" (shape input) (at 374.65 166.37 0) (fields_autoplaced)
    (effects (font (size 1.27 1.27)) (justify left))
    (property "Intersheetrefs" "${INTERSHEET_REFS}" (at -6.35 -29.21 0)
      (effects (font (size 1.27 1.27)) hide)
    )
  )
  (global_label "VCC3V3" (shape input) (at 81.28 219.71 0) (fields_autoplaced)
    (effects (font (size 1.27 1.27)) (justify left))
    (property "Intersheetrefs" "${INTERSHEET_REFS}" (at 90.7472 219.71 0)
      (effects (font (size 1.27 1.27)) (justify left) hide)
    )
  )
  (global_label "ULPI1_STP" (shape input) (at 375.92 80.01 0) (fields_autoplaced)
    (effects (font (size 1.27 1.27)) (justify left))
    (property "Intersheetrefs" "${INTERSHEET_REFS}" (at -5.715 -8.255 0)
      (effects (font (size 1.27 1.27)) hide)
    )
  )
  (global_label "DBG_USB_D_P" (shape input) (at 194.31 62.23 180) (fields_autoplaced)
    (effects (font (size 1.27 1.27)) (justify right))
    (property "Intersheetrefs" "${INTERSHEET_REFS}" (at 31.75 -27.94 0)
      (effects (font (size 1.27 1.27)) hide)
    )
  )
  (global_label "I3C[2]_SCL_3V3" (shape input) (at 55.88 201.93 180) (fields_autoplaced)
    (effects (font (size 1.27 1.27)) (justify right))
    (property "Intersheetrefs" "${INTERSHEET_REFS}" (at 7.62 11.43 0)
      (effects (font (size 1.27 1.27)) hide)
    )
  )
  (global_label "ULPI2_D5" (shape input) (at 374.65 151.13 0) (fields_autoplaced)
    (effects (font (size 1.27 1.27)) (justify left))
    (property "Intersheetrefs" "${INTERSHEET_REFS}" (at -6.35 -24.13 0)
      (effects (font (size 1.27 1.27)) hide)
    )
  )
  (global_label "VCC3V3" (shape input) (at 294.64 81.28 180) (fields_autoplaced)
    (effects (font (size 1.27 1.27)) (justify right))
    (property "Intersheetrefs" "${INTERSHEET_REFS}" (at 26.035 7.62 0)
      (effects (font (size 1.27 1.27)) hide)
    )
  )
  (global_label "MMC_DAT7" (shape input) (at 173.99 265.43 0) (fields_autoplaced)
    (effects (font (size 1.27 1.27)) (justify left))
    (property "Intersheetrefs" "${INTERSHEET_REFS}" (at -3.81 -6.35 0)
      (effects (font (size 1.27 1.27)) hide)
    )
  )
  (global_label "ULPI2_D0" (shape input) (at 374.65 138.43 0) (fields_autoplaced)
    (effects (font (size 1.27 1.27)) (justify left))
    (property "Intersheetrefs" "${INTERSHEET_REFS}" (at -6.35 -49.53 0)
      (effects (font (size 1.27 1.27)) hide)
    )
  )
  (global_label "VCC3V3" (shape input) (at 261.62 224.79 0) (fields_autoplaced)
    (effects (font (size 1.27 1.27)) (justify left))
    (property "Intersheetrefs" "${INTERSHEET_REFS}" (at 10.795 0 0)
      (effects (font (size 1.27 1.27)) hide)
    )
  )
  (global_label "SPI0_CLK" (shape input) (at 322.58 222.25 180) (fields_autoplaced)
    (effects (font (size 1.27 1.27)) (justify right))
    (property "Intersheetrefs" "${INTERSHEET_REFS}" (at 266.7 105.41 0)
      (effects (font (size 1.27 1.27)) hide)
    )
  )
  (global_label "VREGOUT" (shape input) (at 105.41 26.67 180) (fields_autoplaced)
    (effects (font (size 1.27 1.27)) (justify right))
    (property "Intersheetrefs" "${INTERSHEET_REFS}" (at -58.42 -22.86 0)
      (effects (font (size 1.27 1.27)) hide)
    )
  )
  (global_label "ULPI1_D5" (shape input) (at 375.92 64.77 0) (fields_autoplaced)
    (effects (font (size 1.27 1.27)) (justify left))
    (property "Intersheetrefs" "${INTERSHEET_REFS}" (at -5.715 -3.175 0)
      (effects (font (size 1.27 1.27)) hide)
    )
  )
  (global_label "USR_LED1" (shape input) (at 231.14 238.76 180) (fields_autoplaced)
    (effects (font (size 1.27 1.27)) (justify right))
    (property "Intersheetrefs" "${INTERSHEET_REFS}" (at 13.335 0 0)
      (effects (font (size 1.27 1.27)) hide)
    )
  )
  (global_label "ULPI1_D1" (shape input) (at 375.92 54.61 0) (fields_autoplaced)
    (effects (font (size 1.27 1.27)) (justify left))
    (property "Intersheetrefs" "${INTERSHEET_REFS}" (at -5.715 -23.495 0)
      (effects (font (size 1.27 1.27)) hide)
    )
  )
  (global_label "I3C[3]_SDA_3V3" (shape input) (at 55.88 204.47 180) (fields_autoplaced)
    (effects (font (size 1.27 1.27)) (justify right))
    (property "Intersheetrefs" "${INTERSHEET_REFS}" (at 7.62 11.43 0)
      (effects (font (size 1.27 1.27)) hide)
    )
  )
  (global_label "VBUS" (shape input) (at 67.31 39.37 90) (fields_autoplaced)
    (effects (font (size 1.27 1.27)) (justify left))
    (property "Intersheetrefs" "${INTERSHEET_REFS}" (at -20.32 8.89 0)
      (effects (font (size 1.27 1.27)) hide)
    )
  )
  (global_label "VCC3V3" (shape input) (at 74.93 261.62 0) (fields_autoplaced)
    (effects (font (size 1.27 1.27)) (justify left))
    (property "Intersheetrefs" "${INTERSHEET_REFS}" (at 84.3972 261.62 0)
      (effects (font (size 1.27 1.27)) (justify left) hide)
    )
  )
  (global_label "JTAG_TCK" (shape input) (at 250.19 39.37 0) (fields_autoplaced)
    (effects (font (size 1.27 1.27)) (justify left))
    (property "Intersheetrefs" "${INTERSHEET_REFS}" (at 8.89 -5.08 0)
      (effects (font (size 1.27 1.27)) hide)
    )
  )
  (global_label "ULPI1_D2" (shape input) (at 375.92 57.15 0) (fields_autoplaced)
    (effects (font (size 1.27 1.27)) (justify left))
    (property "Intersheetrefs" "${INTERSHEET_REFS}" (at -5.715 -18.415 0)
      (effects (font (size 1.27 1.27)) hide)
    )
  )
  (global_label "MMC_RSTN" (shape input) (at 173.99 242.57 0) (fields_autoplaced)
    (effects (font (size 1.27 1.27)) (justify left))
    (property "Intersheetrefs" "${INTERSHEET_REFS}" (at -3.81 -6.35 0)
      (effects (font (size 1.27 1.27)) hide)
    )
  )
  (global_label "VCC3V3" (shape input) (at 287.02 39.37 180) (fields_autoplaced)
    (effects (font (size 1.27 1.27)) (justify right))
    (property "Intersheetrefs" "${INTERSHEET_REFS}" (at -83.185 12.7 0)
      (effects (font (size 1.27 1.27)) hide)
    )
  )
  (global_label "VCC3V3" (shape input) (at 289.56 167.64 180) (fields_autoplaced)
    (effects (font (size 1.27 1.27)) (justify right))
    (property "Intersheetrefs" "${INTERSHEET_REFS}" (at -43.815 -61.595 0)
      (effects (font (size 1.27 1.27)) hide)
    )
  )
  (global_label "I3C[1]_SDA_3V3" (shape input) (at 55.88 194.31 180) (fields_autoplaced)
    (effects (font (size 1.27 1.27)) (justify right))
    (property "Intersheetrefs" "${INTERSHEET_REFS}" (at 7.62 11.43 0)
      (effects (font (size 1.27 1.27)) hide)
    )
  )
  (global_label "I3C[3]_SDA_3V3" (shape input) (at 97.79 195.58 180) (fields_autoplaced)
    (effects (font (size 1.27 1.27)) (justify right))
    (property "Intersheetrefs" "${INTERSHEET_REFS}" (at -6.35 10.16 0)
      (effects (font (size 1.27 1.27)) hide)
    )
  )
  (global_label "ULPI2_D2" (shape input) (at 374.65 143.51 0) (fields_autoplaced)
    (effects (font (size 1.27 1.27)) (justify left))
    (property "Intersheetrefs" "${INTERSHEET_REFS}" (at -6.35 -39.37 0)
      (effects (font (size 1.27 1.27)) hide)
    )
  )
  (global_label "SPI0_CS_N" (shape input) (at 322.58 224.79 180) (fields_autoplaced)
    (effects (font (size 1.27 1.27)) (justify right))
    (property "Intersheetrefs" "${INTERSHEET_REFS}" (at 266.7 105.41 0)
      (effects (font (size 1.27 1.27)) hide)
    )
  )
  (global_label "USB1_DP" (shape input) (at 341.63 54.61 180) (fields_autoplaced)
    (effects (font (size 1.27 1.27)) (justify right))
    (property "Intersheetrefs" "${INTERSHEET_REFS}" (at 15.875 -6.985 0)
      (effects (font (size 1.27 1.27)) hide)
    )
  )
  (global_label "ULPI2_D4" (shape input) (at 374.65 148.59 0) (fields_autoplaced)
    (effects (font (size 1.27 1.27)) (justify left))
    (property "Intersheetrefs" "${INTERSHEET_REFS}" (at -6.35 -29.21 0)
      (effects (font (size 1.27 1.27)) hide)
    )
  )
  (global_label "I3C[0]_SDA_3V3" (shape input) (at 55.88 189.23 180) (fields_autoplaced)
    (effects (font (size 1.27 1.27)) (justify right))
    (property "Intersheetrefs" "${INTERSHEET_REFS}" (at 7.62 11.43 0)
      (effects (font (size 1.27 1.27)) hide)
    )
  )
  (global_label "DBG_USB_D_N" (shape input) (at 45.72 39.37 0) (fields_autoplaced)
    (effects (font (size 1.27 1.27)) (justify left))
    (property "Intersheetrefs" "${INTERSHEET_REFS}" (at -23.495 -9.525 0)
      (effects (font (size 1.27 1.27)) hide)
    )
  )
  (global_label "VCC3V3" (shape input) (at 48.26 167.64 180) (fields_autoplaced)
    (effects (font (size 1.27 1.27)) (justify right))
    (property "Intersheetrefs" "${INTERSHEET_REFS}" (at 8.255 12.065 0)
      (effects (font (size 1.27 1.27)) hide)
    )
  )
  (global_label "VCC1V0" (shape input) (at 123.19 170.18 0) (fields_autoplaced)
    (effects (font (size 1.27 1.27)) (justify left))
    (property "Intersheetrefs" "${INTERSHEET_REFS}" (at -16.51 6.35 0)
      (effects (font (size 1.27 1.27)) hide)
    )
  )
  (global_label "USB2_DP" (shape input) (at 340.36 140.97 180) (fields_autoplaced)
    (effects (font (size 1.27 1.27)) (justify right))
    (property "Intersheetrefs" "${INTERSHEET_REFS}" (at 15.24 -27.94 0)
      (effects (font (size 1.27 1.27)) hide)
    )
  )
  (global_label "I3C[3]_SCL_3V3" (shape input) (at 55.88 207.01 180) (fields_autoplaced)
    (effects (font (size 1.27 1.27)) (justify right))
    (property "Intersheetrefs" "${INTERSHEET_REFS}" (at 7.62 11.43 0)
      (effects (font (size 1.27 1.27)) hide)
    )
  )
  (global_label "VCC3V3" (shape input) (at 266.7 162.56 90) (fields_autoplaced)
    (effects (font (size 1.27 1.27)) (justify left))
    (property "Intersheetrefs" "${INTERSHEET_REFS}" (at -110.49 -71.12 0)
      (effects (font (size 1.27 1.27)) hide)
    )
  )
  (global_label "MMC_DAT4" (shape input) (at 173.99 257.81 0) (fields_autoplaced)
    (effects (font (size 1.27 1.27)) (justify left))
    (property "Intersheetrefs" "${INTERSHEET_REFS}" (at -3.81 -6.35 0)
      (effects (font (size 1.27 1.27)) hide)
    )
  )
  (global_label "VCC3V3" (shape input) (at 81.28 240.03 180) (fields_autoplaced)
    (effects (font (size 1.27 1.27)) (justify right))
    (property "Intersheetrefs" "${INTERSHEET_REFS}" (at -3.81 2.54 0)
      (effects (font (size 1.27 1.27)) hide)
    )
  )
  (global_label "JTAG_TMS" (shape input) (at 393.7 222.25 0) (fields_autoplaced)
    (effects (font (size 1.27 1.27)) (justify left))
    (property "Intersheetrefs" "${INTERSHEET_REFS}" (at 172.72 52.07 0)
      (effects (font (size 1.27 1.27)) hide)
    )
  )
  (global_label "ULPI_DIR" (shape input) (at 374.65 163.83 0) (fields_autoplaced)
    (effects (font (size 1.27 1.27)) (justify left))
    (property "Intersheetrefs" "${INTERSHEET_REFS}" (at -6.35 -29.21 0)
      (effects (font (size 1.27 1.27)) hide)
    )
  )
  (global_label "JTAG_TMS" (shape input) (at 250.19 46.99 0) (fields_autoplaced)
    (effects (font (size 1.27 1.27)) (justify left))
    (property "Intersheetrefs" "${INTERSHEET_REFS}" (at 8.89 -5.08 0)
      (effects (font (size 1.27 1.27)) hide)
    )
  )
  (global_label "MMC_CMD" (shape input) (at 173.99 245.11 0) (fields_autoplaced)
    (effects (font (size 1.27 1.27)) (justify left))
    (property "Intersheetrefs" "${INTERSHEET_REFS}" (at -3.81 -6.35 0)
      (effects (font (size 1.27 1.27)) hide)
    )
  )
  (global_label "MMC_DAT3" (shape input) (at 173.99 255.27 0) (fields_autoplaced)
    (effects (font (size 1.27 1.27)) (justify left))
    (property "Intersheetrefs" "${INTERSHEET_REFS}" (at -3.81 -6.35 0)
      (effects (font (size 1.27 1.27)) hide)
    )
  )
  (global_label "I3C[0]_SCL_3V3" (shape input) (at 55.88 191.77 180) (fields_autoplaced)
    (effects (font (size 1.27 1.27)) (justify right))
    (property "Intersheetrefs" "${INTERSHEET_REFS}" (at 7.62 11.43 0)
      (effects (font (size 1.27 1.27)) hide)
    )
  )
  (global_label "VBUS" (shape input) (at 45.72 31.75 0) (fields_autoplaced)
    (effects (font (size 1.27 1.27)) (justify left))
    (property "Intersheetrefs" "${INTERSHEET_REFS}" (at -23.495 -14.605 0)
      (effects (font (size 1.27 1.27)) hide)
    )
  )
  (global_label "ULPI1_DIR" (shape input) (at 375.92 77.47 0) (fields_autoplaced)
    (effects (font (size 1.27 1.27)) (justify left))
    (property "Intersheetrefs" "${INTERSHEET_REFS}" (at -5.715 -8.255 0)
      (effects (font (size 1.27 1.27)) hide)
    )
  )
  (global_label "ULPI2_CLKO" (shape input) (at 374.65 168.91 0) (fields_autoplaced)
    (effects (font (size 1.27 1.27)) (justify left))
    (property "Intersheetrefs" "${INTERSHEET_REFS}" (at -6.35 -29.21 0)
      (effects (font (size 1.27 1.27)) hide)
    )
  )
  (global_label "ULPI1_D7" (shape input) (at 375.92 69.85 0) (fields_autoplaced)
    (effects (font (size 1.27 1.27)) (justify left))
    (property "Intersheetrefs" "${INTERSHEET_REFS}" (at -5.715 6.985 0)
      (effects (font (size 1.27 1.27)) hide)
    )
  )
  (global_label "I3C[3]_SCL_1V0" (shape input) (at 123.19 193.04 0) (fields_autoplaced)
    (effects (font (size 1.27 1.27)) (justify left))
    (property "Intersheetrefs" "${INTERSHEET_REFS}" (at -16.51 10.16 0)
      (effects (font (size 1.27 1.27)) hide)
    )
  )
  (global_label "I3C[1]_SCL_3V3" (shape input) (at 97.79 182.88 180) (fields_autoplaced)
    (effects (font (size 1.27 1.27)) (justify right))
    (property "Intersheetrefs" "${INTERSHEET_REFS}" (at -6.35 10.16 0)
      (effects (font (size 1.27 1.27)) hide)
    )
  )
  (global_label "ULPI1_D0" (shape input) (at 375.92 52.07 0) (fields_autoplaced)
    (effects (font (size 1.27 1.27)) (justify left))
    (property "Intersheetrefs" "${INTERSHEET_REFS}" (at -5.715 -28.575 0)
      (effects (font (size 1.27 1.27)) hide)
    )
  )
  (global_label "ULPI1_D6" (shape input) (at 375.92 67.31 0) (fields_autoplaced)
    (effects (font (size 1.27 1.27)) (justify left))
    (property "Intersheetrefs" "${INTERSHEET_REFS}" (at -5.715 1.905 0)
      (effects (font (size 1.27 1.27)) hide)
    )
  )
  (global_label "MMC_CLK" (shape input) (at 173.99 240.03 0) (fields_autoplaced)
    (effects (font (size 1.27 1.27)) (justify left))
    (property "Intersheetrefs" "${INTERSHEET_REFS}" (at -3.81 -6.35 0)
      (effects (font (size 1.27 1.27)) hide)
    )
  )
  (global_label "VCC3V3" (shape input) (at 341.63 46.99 180) (fields_autoplaced)
    (effects (font (size 1.27 1.27)) (justify right))
    (property "Intersheetrefs" "${INTERSHEET_REFS}" (at 13.97 -40.005 0)
      (effects (font (size 1.27 1.27)) hide)
    )
  )
  (global_label "ULPI1_NXT" (shape input) (at 375.92 74.93 0) (fields_autoplaced)
    (effects (font (size 1.27 1.27)) (justify left))
    (property "Intersheetrefs" "${INTERSHEET_REFS}" (at -5.715 -8.255 0)
      (effects (font (size 1.27 1.27)) hide)
    )
  )
  (global_label "ULPI2_D1" (shape input) (at 374.65 140.97 0) (fields_autoplaced)
    (effects (font (size 1.27 1.27)) (justify left))
    (property "Intersheetrefs" "${INTERSHEET_REFS}" (at -6.35 -44.45 0)
      (effects (font (size 1.27 1.27)) hide)
    )
  )
  (global_label "SPI0_MOSI" (shape input) (at 322.58 217.17 180) (fields_autoplaced)
    (effects (font (size 1.27 1.27)) (justify right))
    (property "Intersheetrefs" "${INTERSHEET_REFS}" (at 266.7 105.41 0)
      (effects (font (size 1.27 1.27)) hide)
    )
  )
  (global_label "I3C[2]_SCL_1V0" (shape input) (at 123.19 187.96 0) (fields_autoplaced)
    (effects (font (size 1.27 1.27)) (justify left))
    (property "Intersheetrefs" "${INTERSHEET_REFS}" (at -16.51 10.16 0)
      (effects (font (size 1.27 1.27)) hide)
    )
  )
  (global_label "I3C[2]_SDA_3V3" (shape input) (at 55.88 199.39 180) (fields_autoplaced)
    (effects (font (size 1.27 1.27)) (justify right))
    (property "Intersheetrefs" "${INTERSHEET_REFS}" (at 7.62 11.43 0)
      (effects (font (size 1.27 1.27)) hide)
    )
  )
  (global_label "VBUS" (shape input) (at 73.66 39.37 90) (fields_autoplaced)
    (effects (font (size 1.27 1.27)) (justify left))
    (property "Intersheetrefs" "${INTERSHEET_REFS}" (at -20.32 8.89 0)
      (effects (font (size 1.27 1.27)) hide)
    )
  )
  (global_label "VCC3V3" (shape input) (at 279.4 77.47 90) (fields_autoplaced)
    (effects (font (size 1.27 1.27)) (justify left))
    (property "Intersheetrefs" "${INTERSHEET_REFS}" (at -33.02 -0.635 0)
      (effects (font (size 1.27 1.27)) hide)
    )
  )
  (global_label "VBUS" (shape input) (at 254 107.95 0) (fields_autoplaced)
    (effects (font (size 1.27 1.27)) (justify left))
    (property "Intersheetrefs" "${INTERSHEET_REFS}" (at 8.89 -5.715 0)
      (effects (font (size 1.27 1.27)) hide)
    )
  )
  (global_label "USB2_DN" (shape input) (at 340.36 138.43 180) (fields_autoplaced)
    (effects (font (size 1.27 1.27)) (justify right))
    (property "Intersheetrefs" "${INTERSHEET_REFS}" (at 15.24 -27.94 0)
      (effects (font (size 1.27 1.27)) hide)
    )
  )
  (global_label "MMC_DAT2" (shape input) (at 173.99 252.73 0) (fields_autoplaced)
    (effects (font (size 1.27 1.27)) (justify left))
    (property "Intersheetrefs" "${INTERSHEET_REFS}" (at -3.81 -6.35 0)
      (effects (font (size 1.27 1.27)) hide)
    )
  )
  (global_label "I3C[0]_SDA_3V3" (shape input) (at 97.79 180.34 180) (fields_autoplaced)
    (effects (font (size 1.27 1.27)) (justify right))
    (property "Intersheetrefs" "${INTERSHEET_REFS}" (at -6.35 10.16 0)
      (effects (font (size 1.27 1.27)) hide)
    )
  )
  (global_label "VCC3V3" (shape input) (at 113.03 46.99 180) (fields_autoplaced)
    (effects (font (size 1.27 1.27)) (justify right))
    (property "Intersheetrefs" "${INTERSHEET_REFS}" (at 67.31 166.37 0)
      (effects (font (size 1.27 1.27)) hide)
    )
  )
  (global_label "ULPI2_RESET" (shape input) (at 374.65 171.45 0) (fields_autoplaced)
    (effects (font (size 1.27 1.27)) (justify left))
    (property "Intersheetrefs" "${INTERSHEET_REFS}" (at -6.35 -29.21 0)
      (effects (font (size 1.27 1.27)) hide)
    )
  )
  (global_label "VCC3V3" (shape input) (at 261.62 270.51 0) (fields_autoplaced)
    (effects (font (size 1.27 1.27)) (justify left))
    (property "Intersheetrefs" "${INTERSHEET_REFS}" (at 10.16 0 0)
      (effects (font (size 1.27 1.27)) hide)
    )
  )
  (global_label "JTAG_TDO" (shape input) (at 393.7 227.33 0) (fields_autoplaced)
    (effects (font (size 1.27 1.27)) (justify left))
    (property "Intersheetrefs" "${INTERSHEET_REFS}" (at 172.72 52.07 0)
      (effects (font (size 1.27 1.27)) hide)
    )
  )
  (global_label "VCC3V3" (shape input) (at 163.83 64.77 180) (fields_autoplaced)
    (effects (font (size 1.27 1.27)) (justify right))
    (property "Intersheetrefs" "${INTERSHEET_REFS}" (at 8.89 -27.94 0)
      (effects (font (size 1.27 1.27)) hide)
    )
  )
  (global_label "ULPI2_D6" (shape input) (at 374.65 153.67 0) (fields_autoplaced)
    (effects (font (size 1.27 1.27)) (justify left))
    (property "Intersheetrefs" "${INTERSHEET_REFS}" (at -6.35 -19.05 0)
      (effects (font (size 1.27 1.27)) hide)
    )
  )
  (global_label "VCC3V3" (shape input) (at 129.54 97.79 90) (fields_autoplaced)
    (effects (font (size 1.27 1.27)) (justify left))
    (property "Intersheetrefs" "${INTERSHEET_REFS}" (at -13.335 -20.955 0)
      (effects (font (size 1.27 1.27)) hide)
    )
  )
  (global_label "I3C[1]_SDA_1V0" (shape input) (at 123.19 185.42 0) (fields_autoplaced)
    (effects (font (size 1.27 1.27)) (justify left))
    (property "Intersheetrefs" "${INTERSHEET_REFS}" (at -16.51 10.16 0)
      (effects (font (size 1.27 1.27)) hide)
    )
  )
  (global_label "ULPI2_D3" (shape input) (at 374.65 146.05 0) (fields_autoplaced)
    (effects (font (size 1.27 1.27)) (justify left))
    (property "Intersheetrefs" "${INTERSHEET_REFS}" (at -6.35 -34.29 0)
      (effects (font (size 1.27 1.27)) hide)
    )
  )
  (global_label "VCC3V3" (shape input) (at 340.36 133.35 180) (fields_autoplaced)
    (effects (font (size 1.27 1.27)) (justify right))
    (property "Intersheetrefs" "${INTERSHEET_REFS}" (at 13.335 -60.96 0)
      (effects (font (size 1.27 1.27)) hide)
    )
  )
  (global_label "I3C[3]_SCL_3V3" (shape input) (at 97.79 193.04 180) (fields_autoplaced)
    (effects (font (size 1.27 1.27)) (justify right))
    (property "Intersheetrefs" "${INTERSHEET_REFS}" (at -6.35 10.16 0)
      (effects (font (size 1.27 1.27)) hide)
    )
  )
  (global_label "JTAG_TCK" (shape input) (at 393.7 224.79 0) (fields_autoplaced)
    (effects (font (size 1.27 1.27)) (justify left))
    (property "Intersheetrefs" "${INTERSHEET_REFS}" (at 172.72 52.07 0)
      (effects (font (size 1.27 1.27)) hide)
    )
  )
  (global_label "I3C[0]_SCL_1V0" (shape input) (at 123.19 177.8 0) (fields_autoplaced)
    (effects (font (size 1.27 1.27)) (justify left))
    (property "Intersheetrefs" "${INTERSHEET_REFS}" (at -16.51 10.16 0)
      (effects (font (size 1.27 1.27)) hide)
    )
  )
  (global_label "ULPI1_D4" (shape input) (at 375.92 62.23 0) (fields_autoplaced)
    (effects (font (size 1.27 1.27)) (justify left))
    (property "Intersheetrefs" "${INTERSHEET_REFS}" (at -5.715 -8.255 0)
      (effects (font (size 1.27 1.27)) hide)
    )
  )
  (global_label "VCC5V0" (shape input) (at 327.66 62.23 180) (fields_autoplaced)
    (effects (font (size 1.27 1.27)) (justify right))
    (property "Intersheetrefs" "${INTERSHEET_REFS}" (at 318.1928 62.23 0)
      (effects (font (size 1.27 1.27)) (justify right) hide)
    )
  )
  (global_label "ULPI2_D7" (shape input) (at 374.65 156.21 0) (fields_autoplaced)
    (effects (font (size 1.27 1.27)) (justify left))
    (property "Intersheetrefs" "${INTERSHEET_REFS}" (at -6.35 -13.97 0)
      (effects (font (size 1.27 1.27)) hide)
    )
  )
  (global_label "JTAG_TDO" (shape input) (at 250.19 44.45 0) (fields_autoplaced)
    (effects (font (size 1.27 1.27)) (justify left))
    (property "Intersheetrefs" "${INTERSHEET_REFS}" (at 8.89 -5.08 0)
      (effects (font (size 1.27 1.27)) hide)
    )
  )
  (global_label "VCC3V3" (shape input) (at 173.99 220.98 0) (fields_autoplaced)
    (effects (font (size 1.27 1.27)) (justify left))
    (property "Intersheetrefs" "${INTERSHEET_REFS}" (at 183.4572 220.98 0)
      (effects (font (size 1.27 1.27)) (justify left) hide)
    )
  )
  (global_label "I3C[1]_SCL_3V3" (shape input) (at 55.88 196.85 180) (fields_autoplaced)
    (effects (font (size 1.27 1.27)) (justify right))
    (property "Intersheetrefs" "${INTERSHEET_REFS}" (at 7.62 11.43 0)
      (effects (font (size 1.27 1.27)) hide)
    )
  )
  (global_label "MMC_DAT5" (shape input) (at 173.99 260.35 0) (fields_autoplaced)
    (effects (font (size 1.27 1.27)) (justify left))
    (property "Intersheetrefs" "${INTERSHEET_REFS}" (at -3.81 -6.35 0)
      (effects (font (size 1.27 1.27)) hide)
    )
  )
  (global_label "JTAG_TDI" (shape input) (at 250.19 41.91 0) (fields_autoplaced)
    (effects (font (size 1.27 1.27)) (justify left))
    (property "Intersheetrefs" "${INTERSHEET_REFS}" (at 8.89 -5.08 0)
      (effects (font (size 1.27 1.27)) hide)
    )
  )
  (global_label "VBUS" (shape input) (at 163.83 67.31 180) (fields_autoplaced)
    (effects (font (size 1.27 1.27)) (justify right))
    (property "Intersheetrefs" "${INTERSHEET_REFS}" (at 8.89 -27.94 0)
      (effects (font (size 1.27 1.27)) hide)
    )
  )
  (global_label "VCC3V3" (shape input) (at 113.03 60.96 180) (fields_autoplaced)
    (effects (font (size 1.27 1.27)) (justify right))
    (property "Intersheetrefs" "${INTERSHEET_REFS}" (at 50.8 179.705 0)
      (effects (font (size 1.27 1.27)) hide)
    )
  )
  (global_label "VCC3V3" (shape input) (at 294.64 116.84 180) (fields_autoplaced)
    (effects (font (size 1.27 1.27)) (justify right))
    (property "Intersheetrefs" "${INTERSHEET_REFS}" (at -74.295 -13.97 0)
      (effects (font (size 1.27 1.27)) hide)
    )
  )
  (global_label "1V0_PG" (shape input) (at 80.01 161.29 180) (fields_autoplaced)
    (effects (font (size 1.27 1.27)) (justify right))
    (property "Intersheetrefs" "${INTERSHEET_REFS}" (at -15.875 8.89 0)
      (effects (font (size 1.27 1.27)) hide)
    )
  )
  (global_label "DBG_USB_D_N" (shape input) (at 194.31 64.77 180) (fields_autoplaced)
    (effects (font (size 1.27 1.27)) (justify right))
    (property "Intersheetrefs" "${INTERSHEET_REFS}" (at 31.75 -22.86 0)
      (effects (font (size 1.27 1.27)) hide)
    )
  )
  (global_label "MMC_DAT6" (shape input) (at 173.99 262.89 0) (fields_autoplaced)
    (effects (font (size 1.27 1.27)) (justify left))
    (property "Intersheetrefs" "${INTERSHEET_REFS}" (at -3.81 -6.35 0)
      (effects (font (size 1.27 1.27)) hide)
    )
  )
  (global_label "ULPI1_D3" (shape input) (at 375.92 59.69 0) (fields_autoplaced)
    (effects (font (size 1.27 1.27)) (justify left))
    (property "Intersheetrefs" "${INTERSHEET_REFS}" (at -5.715 -13.335 0)
      (effects (font (size 1.27 1.27)) hide)
    )
  )
  (global_label "VCC5V0" (shape input) (at 335.28 148.59 180) (fields_autoplaced)
    (effects (font (size 1.27 1.27)) (justify right))
    (property "Intersheetrefs" "${INTERSHEET_REFS}" (at 24.13 -15.24 0)
      (effects (font (size 1.27 1.27)) hide)
    )
  )
  (global_label "SPI0_MISO" (shape input) (at 322.58 219.71 180) (fields_autoplaced)
    (effects (font (size 1.27 1.27)) (justify right))
    (property "Intersheetrefs" "${INTERSHEET_REFS}" (at 266.7 105.41 0)
      (effects (font (size 1.27 1.27)) hide)
    )
  )

  (symbol (lib_id "antmicropower:GND") (at 398.78 238.76 0) (unit 1)
    (in_bom yes) (on_board yes) (dnp no)
    (property "Reference" "#PWR034" (at 398.78 245.11 0)
      (effects (font (size 1.27 1.27)) hide)
    )
    (property "Value" "GND" (at 398.907 243.1542 0)
      (effects (font (size 1.27 1.27)))
    )
    (property "Footprint" "" (at 398.78 238.76 0)
      (effects (font (size 1.27 1.27)) hide)
    )
    (property "Datasheet" "" (at 398.78 238.76 0)
      (effects (font (size 1.27 1.27)) hide)
    )
    (property "Author" "Antmicro" (at 407.67 246.38 0)
      (effects (font (size 1.27 1.27) (thickness 0.15)) (justify left bottom) hide)
    )
    (property "License" "Apache-2.0" (at 407.67 248.92 0)
      (effects (font (size 1.27 1.27) (thickness 0.15)) (justify left bottom) hide)
    )
    (pin "1")
    (instances
      (project "ecp5-dc-scm"
        (path ""
          (reference "#PWR034") (unit 1)
        )
      )
    )
  )

  (symbol (lib_id "antmicroMemory:MTFC16GAPALNA-AIT") (at 120.65 240.03 0) (mirror y) (unit 1)
    (in_bom yes) (on_board yes) (dnp no) (fields_autoplaced)
    (property "Reference" "U6" (at 110.49 233.045 0)
      (effects (font (size 1.27 1.27)))
    )
    (property "Value" "MTFC16GAPALNA-AIT" (at 110.49 233.045 0)
      (effects (font (size 1.27 1.27)) hide)
    )
    (property "Footprint" "antmicro-footprints:BGA-170-100_18x14mm_Layout17x10_P1mm" (at 106.68 234.95 0)
      (effects (font (size 1.27 1.27)) (justify left bottom) hide)
    )
    (property "Datasheet" "https://www.mouser.com/datasheet/2/671/micron_technology_mict-s-a0006806196-1-1759129.pdf" (at 120.65 240.03 0)
      (effects (font (size 1.27 1.27)) (justify left bottom) hide)
    )
    (property "MANUFACTURER" "Micron" (at 120.65 240.03 0)
      (effects (font (size 1.27 1.27)) (justify left bottom) hide)
    )
    (property "Package" "100-ball TBGA 14x18" (at 120.65 222.885 0)
      (effects (font (size 1.27 1.27)) hide)
    )
    (property "Manufacturer" "Micron Technology" (at 87.63 252.73 0)
      (effects (font (size 1.27 1.27) (thickness 0.15)) (justify left bottom) hide)
    )
    (property "MPN" "MTFC16GAPALNA-AIT" (at 110.49 235.585 0)
      (effects (font (size 1.27 1.27) (thickness 0.15)))
    )
    (property "Author" "Antmicro" (at 87.63 257.81 0)
      (effects (font (size 1.27 1.27) (thickness 0.15)) (justify left bottom) hide)
    )
    (property "License" "Apache-2.0" (at 87.63 260.35 0)
      (effects (font (size 1.27 1.27) (thickness 0.15)) (justify left bottom) hide)
    )
    (pin "E4")
    (pin "F2")
    (pin "H2")
    (pin "H3")
    (pin "H8")
    (pin "H9")
    (pin "K2")
    (pin "K3")
    (pin "K5")
    (pin "K8")
    (pin "K9")
    (pin "L2")
    (pin "L3")
    (pin "L4")
    (pin "L7")
    (pin "L8")
    (pin "L9")
    (pin "M4")
    (pin "M5")
    (pin "M7")
    (pin "N2")
    (pin "N3")
    (pin "N8")
    (pin "N9")
    (pin "P2")
    (pin "P3")
    (pin "P5")
    (pin "P6")
    (pin "P8")
    (pin "P9")
    (pin "F3")
    (pin "F4")
    (pin "F5")
    (pin "F6")
    (pin "F7")
    (pin "F8")
    (pin "F9")
    (pin "G2")
    (pin "G3")
    (pin "G4")
    (pin "G5")
    (pin "G6")
    (pin "G7")
    (pin "G8")
    (pin "G9")
    (pin "J5")
    (pin "J4")
    (pin "J6")
    (pin "J7")
    (pin "J8")
    (pin "J9")
    (pin "L5")
    (pin "L6")
    (pin "D9")
    (pin "E2")
    (pin "E3")
    (pin "E5")
    (pin "A1")
    (pin "P4")
    (pin "U9")
    (pin "A9")
    (pin "B1")
    (pin "B10")
    (pin "D2")
    (pin "D3")
    (pin "E6")
    (pin "E7")
    (pin "E8")
    (pin "E9")
    (pin "H4")
    (pin "H5")
    (pin "H6")
    (pin "T1")
    (pin "T10")
    (pin "U1")
    (pin "U10")
    (pin "U2")
    (pin "P7")
    (pin "K7")
    (pin "M2")
    (pin "M3")
    (pin "M6")
    (pin "M8")
    (pin "M9")
    (pin "A10")
    (pin "D4")
    (pin "D5")
    (pin "D6")
    (pin "D7")
    (pin "D8")
    (pin "N4")
    (pin "N5")
    (pin "N6")
    (pin "N7")
    (pin "H7")
    (pin "J2")
    (pin "J3")
    (pin "A2")
    (pin "K4")
    (pin "K6")
    (instances
      (project "ecp5-dc-scm"
        (path ""
          (reference "U6") (unit 1)
        )
      )
    )
  )

  (symbol (lib_id "antmicroCapacitors0402:C_100n_0402") (at 67.31 48.26 90) (unit 1)
    (in_bom yes) (on_board yes) (dnp no) (fields_autoplaced)
    (property "Reference" "C98" (at 64.77 44.4436 90)
      (effects (font (size 1.524 1.524)) (justify left))
    )
    (property "Value" "C_100n_0402" (at 71.12 48.26 0)
      (effects (font (size 1.524 1.524)) hide)
    )
    (property "Footprint" "antmicro-footprints:C_0402_1005Metric" (at 62.23 43.18 0)
      (effects (font (size 1.524 1.524)) (justify left) hide)
    )
    (property "Datasheet" "https://www.murata.com/products/productdetail?partno=GRM155R61H104KE14%23" (at 67.31 48.26 0)
      (effects (font (size 1.27 1.27)) hide)
    )
    (property "Manufacturer" "Murata" (at 57.15 43.18 0)
      (effects (font (size 1.524 1.524)) (justify left) hide)
    )
    (property "MPN" "GRM155R61H104KE14D" (at 59.69 43.18 0)
      (effects (font (size 1.524 1.524)) (justify left) hide)
    )
    (property "Val" "100n" (at 64.77 46.9836 90)
      (effects (font (size 1.27 1.27)) (justify left))
    )
    (property "License" "Apache-2.0" (at 90.17 27.94 0)
      (effects (font (size 1.27 1.27) (thickness 0.15)) (justify left bottom) hide)
    )
    (property "Author" "Antmicro" (at 92.71 27.94 0)
      (effects (font (size 1.27 1.27) (thickness 0.15)) (justify left bottom) hide)
    )
    (property "Voltage" "50V" (at 95.25 27.94 0)
      (effects (font (size 1.27 1.27)) (justify left bottom) hide)
    )
    (property "Dielectric" "X5R" (at 97.79 27.94 0)
      (effects (font (size 1.27 1.27)) (justify left bottom) hide)
    )
    (property "Public" "False" (at 100.33 27.94 0)
      (effects (font (size 1.27 1.27)) (justify left bottom) hide)
    )
    (pin "1")
    (pin "2")
    (instances
      (project "ecp5-dc-scm"
        (path ""
          (reference "C98") (unit 1)
        )
      )
    )
  )

  (symbol (lib_id "antmicroCapacitors0402:C_4u7_0402") (at 73.66 48.26 90) (unit 1)
    (in_bom yes) (on_board yes) (dnp no) (fields_autoplaced)
    (property "Reference" "C99" (at 76.2 44.4436 90)
      (effects (font (size 1.524 1.524)) (justify right))
    )
    (property "Value" "C_4u7_0402" (at 77.47 48.26 0)
      (effects (font (size 1.524 1.524)) hide)
    )
    (property "Footprint" "antmicro-footprints:C_0402_1005Metric" (at 68.58 43.18 0)
      (effects (font (size 1.524 1.524)) (justify left) hide)
    )
    (property "Datasheet" "https://www.murata.com/products/productdetail?partno=GRM155R61A475MEAA%23" (at 73.66 48.26 0)
      (effects (font (size 1.27 1.27)) hide)
    )
    (property "Manufacturer" "Murata" (at 63.5 43.18 0)
      (effects (font (size 1.524 1.524)) (justify left) hide)
    )
    (property "MPN" "GRM155R61A475MEAAD" (at 66.04 43.18 0)
      (effects (font (size 1.524 1.524)) (justify left) hide)
    )
    (property "Val" "4u7" (at 76.2 46.9836 90)
      (effects (font (size 1.27 1.27)) (justify right))
    )
    (property "License" "Apache-2.0" (at 96.52 27.94 0)
      (effects (font (size 1.27 1.27) (thickness 0.15)) (justify left bottom) hide)
    )
    (property "Author" "Antmicro" (at 99.06 27.94 0)
      (effects (font (size 1.27 1.27) (thickness 0.15)) (justify left bottom) hide)
    )
    (property "Voltage" "" (at 101.6 27.94 0)
      (effects (font (size 1.27 1.27)) (justify left bottom) hide)
    )
    (property "Dielectric" "" (at 104.14 27.94 0)
      (effects (font (size 1.27 1.27)) (justify left bottom) hide)
    )
    (property "Public" "False" (at 106.68 27.94 0)
      (effects (font (size 1.27 1.27)) (justify left bottom) hide)
    )
    (pin "1")
    (pin "2")
    (instances
      (project "ecp5-dc-scm"
        (path ""
          (reference "C99") (unit 1)
        )
      )
    )
  )

  (symbol (lib_id "antmicropower:GND") (at 67.31 49.53 0) (unit 1)
    (in_bom yes) (on_board yes) (dnp no)
    (property "Reference" "#PWR0151" (at 67.31 55.88 0)
      (effects (font (size 1.27 1.27)) hide)
    )
    (property "Value" "GND" (at 67.437 53.9242 0)
      (effects (font (size 1.27 1.27)))
    )
    (property "Footprint" "" (at 67.31 49.53 0)
      (effects (font (size 1.27 1.27)) hide)
    )
    (property "Datasheet" "" (at 67.31 49.53 0)
      (effects (font (size 1.27 1.27)) hide)
    )
    (property "Author" "Antmicro" (at 76.2 57.15 0)
      (effects (font (size 1.27 1.27) (thickness 0.15)) (justify left bottom) hide)
    )
    (property "License" "Apache-2.0" (at 76.2 59.69 0)
      (effects (font (size 1.27 1.27) (thickness 0.15)) (justify left bottom) hide)
    )
    (pin "1")
    (instances
      (project "ecp5-dc-scm"
        (path ""
          (reference "#PWR0151") (unit 1)
        )
      )
    )
  )

  (symbol (lib_id "antmicropower:GND") (at 73.66 49.53 0) (unit 1)
    (in_bom yes) (on_board yes) (dnp no)
    (property "Reference" "#PWR0152" (at 73.66 55.88 0)
      (effects (font (size 1.27 1.27)) hide)
    )
    (property "Value" "GND" (at 73.787 53.9242 0)
      (effects (font (size 1.27 1.27)))
    )
    (property "Footprint" "" (at 73.66 49.53 0)
      (effects (font (size 1.27 1.27)) hide)
    )
    (property "Datasheet" "" (at 73.66 49.53 0)
      (effects (font (size 1.27 1.27)) hide)
    )
    (property "Author" "Antmicro" (at 82.55 57.15 0)
      (effects (font (size 1.27 1.27) (thickness 0.15)) (justify left bottom) hide)
    )
    (property "License" "Apache-2.0" (at 82.55 59.69 0)
      (effects (font (size 1.27 1.27) (thickness 0.15)) (justify left bottom) hide)
    )
    (pin "1")
    (instances
      (project "ecp5-dc-scm"
        (path ""
          (reference "#PWR0152") (unit 1)
        )
      )
    )
  )

  (symbol (lib_id "antmicroResistors0402:R_47k_0402") (at 129.54 228.6 270) (unit 1)
    (in_bom yes) (on_board yes) (dnp no)
    (property "Reference" "R59" (at 130.81 223.52 0)
      (effects (font (size 1.524 1.524)) (justify left))
    )
    (property "Value" "R_47k_0402" (at 125.73 228.6 0)
      (effects (font (size 1.524 1.524)) hide)
    )
    (property "Footprint" "antmicro-footprints:R_0402_1005Metric" (at 134.62 233.68 0)
      (effects (font (size 1.524 1.524)) (justify left) hide)
    )
    (property "Datasheet" "https://www.bourns.com/docs/product-datasheets/cr.pdf" (at 129.54 228.6 0)
      (effects (font (size 1.27 1.27)) hide)
    )
    (property "Manufacturer" "Bourns" (at 139.7 233.68 0)
      (effects (font (size 1.524 1.524)) (justify left) hide)
    )
    (property "MPN" "CR0402-FX-4702GLF" (at 137.16 233.68 0)
      (effects (font (size 1.524 1.524)) (justify left) hide)
    )
    (property "Val" "47k" (at 130.81 233.68 0)
      (effects (font (size 1.27 1.27)) (justify left))
    )
    (property "License" "Apache-2.0" (at 104.14 248.92 0)
      (effects (font (size 1.27 1.27) (thickness 0.15)) (justify left bottom) hide)
    )
    (property "Author" "Antmicro" (at 101.6 248.92 0)
      (effects (font (size 1.27 1.27) (thickness 0.15)) (justify left bottom) hide)
    )
    (property "Tolerance" "1%" (at 119.38 248.92 0)
      (effects (font (size 1.27 1.27)) (justify left bottom) hide)
    )
    (property "Public" "False" (at 99.06 248.92 0)
      (effects (font (size 1.27 1.27)) (justify left bottom) hide)
    )
    (pin "1")
    (pin "2")
    (instances
      (project "ecp5-dc-scm"
        (path ""
          (reference "R59") (unit 1)
        )
      )
    )
  )

  (symbol (lib_id "antmicroResistors0402:R_47k_0402") (at 133.35 228.6 270) (unit 1)
    (in_bom yes) (on_board yes) (dnp no)
    (property "Reference" "R60" (at 134.62 223.52 0)
      (effects (font (size 1.524 1.524)) (justify left))
    )
    (property "Value" "R_47k_0402" (at 129.54 228.6 0)
      (effects (font (size 1.524 1.524)) hide)
    )
    (property "Footprint" "antmicro-footprints:R_0402_1005Metric" (at 138.43 233.68 0)
      (effects (font (size 1.524 1.524)) (justify left) hide)
    )
    (property "Datasheet" "https://www.bourns.com/docs/product-datasheets/cr.pdf" (at 133.35 228.6 0)
      (effects (font (size 1.27 1.27)) hide)
    )
    (property "Manufacturer" "Bourns" (at 143.51 233.68 0)
      (effects (font (size 1.524 1.524)) (justify left) hide)
    )
    (property "MPN" "CR0402-FX-4702GLF" (at 140.97 233.68 0)
      (effects (font (size 1.524 1.524)) (justify left) hide)
    )
    (property "Val" "47k" (at 134.62 233.68 0)
      (effects (font (size 1.27 1.27)) (justify left))
    )
    (property "License" "Apache-2.0" (at 107.95 248.92 0)
      (effects (font (size 1.27 1.27) (thickness 0.15)) (justify left bottom) hide)
    )
    (property "Author" "Antmicro" (at 105.41 248.92 0)
      (effects (font (size 1.27 1.27) (thickness 0.15)) (justify left bottom) hide)
    )
    (property "Tolerance" "1%" (at 123.19 248.92 0)
      (effects (font (size 1.27 1.27)) (justify left bottom) hide)
    )
    (property "Public" "False" (at 102.87 248.92 0)
      (effects (font (size 1.27 1.27)) (justify left bottom) hide)
    )
    (pin "1")
    (pin "2")
    (instances
      (project "ecp5-dc-scm"
        (path ""
          (reference "R60") (unit 1)
        )
      )
    )
  )

  (symbol (lib_id "antmicroResistors0402:R_47k_0402") (at 138.43 228.6 270) (unit 1)
    (in_bom yes) (on_board yes) (dnp no)
    (property "Reference" "R61" (at 139.7 223.52 0)
      (effects (font (size 1.524 1.524)) (justify left))
    )
    (property "Value" "R_47k_0402" (at 134.62 228.6 0)
      (effects (font (size 1.524 1.524)) hide)
    )
    (property "Footprint" "antmicro-footprints:R_0402_1005Metric" (at 143.51 233.68 0)
      (effects (font (size 1.524 1.524)) (justify left) hide)
    )
    (property "Datasheet" "https://www.bourns.com/docs/product-datasheets/cr.pdf" (at 138.43 228.6 0)
      (effects (font (size 1.27 1.27)) hide)
    )
    (property "Manufacturer" "Bourns" (at 148.59 233.68 0)
      (effects (font (size 1.524 1.524)) (justify left) hide)
    )
    (property "MPN" "CR0402-FX-4702GLF" (at 146.05 233.68 0)
      (effects (font (size 1.524 1.524)) (justify left) hide)
    )
    (property "Val" "47k" (at 139.7 233.68 0)
      (effects (font (size 1.27 1.27)) (justify left))
    )
    (property "License" "Apache-2.0" (at 113.03 248.92 0)
      (effects (font (size 1.27 1.27) (thickness 0.15)) (justify left bottom) hide)
    )
    (property "Author" "Antmicro" (at 110.49 248.92 0)
      (effects (font (size 1.27 1.27) (thickness 0.15)) (justify left bottom) hide)
    )
    (property "Tolerance" "1%" (at 128.27 248.92 0)
      (effects (font (size 1.27 1.27)) (justify left bottom) hide)
    )
    (property "Public" "False" (at 107.95 248.92 0)
      (effects (font (size 1.27 1.27)) (justify left bottom) hide)
    )
    (pin "1")
    (pin "2")
    (instances
      (project "ecp5-dc-scm"
        (path ""
          (reference "R61") (unit 1)
        )
      )
    )
  )

  (symbol (lib_id "antmicroResistors0402:R_47k_0402") (at 142.24 228.6 270) (unit 1)
    (in_bom yes) (on_board yes) (dnp no)
    (property "Reference" "R62" (at 143.51 223.52 0)
      (effects (font (size 1.524 1.524)) (justify left))
    )
    (property "Value" "R_47k_0402" (at 138.43 228.6 0)
      (effects (font (size 1.524 1.524)) hide)
    )
    (property "Footprint" "antmicro-footprints:R_0402_1005Metric" (at 147.32 233.68 0)
      (effects (font (size 1.524 1.524)) (justify left) hide)
    )
    (property "Datasheet" "https://www.bourns.com/docs/product-datasheets/cr.pdf" (at 142.24 228.6 0)
      (effects (font (size 1.27 1.27)) hide)
    )
    (property "Manufacturer" "Bourns" (at 152.4 233.68 0)
      (effects (font (size 1.524 1.524)) (justify left) hide)
    )
    (property "MPN" "CR0402-FX-4702GLF" (at 149.86 233.68 0)
      (effects (font (size 1.524 1.524)) (justify left) hide)
    )
    (property "Val" "47k" (at 143.51 233.68 0)
      (effects (font (size 1.27 1.27)) (justify left))
    )
    (property "License" "Apache-2.0" (at 116.84 248.92 0)
      (effects (font (size 1.27 1.27) (thickness 0.15)) (justify left bottom) hide)
    )
    (property "Author" "Antmicro" (at 114.3 248.92 0)
      (effects (font (size 1.27 1.27) (thickness 0.15)) (justify left bottom) hide)
    )
    (property "Tolerance" "1%" (at 132.08 248.92 0)
      (effects (font (size 1.27 1.27)) (justify left bottom) hide)
    )
    (property "Public" "False" (at 111.76 248.92 0)
      (effects (font (size 1.27 1.27)) (justify left bottom) hide)
    )
    (pin "1")
    (pin "2")
    (instances
      (project "ecp5-dc-scm"
        (path ""
          (reference "R62") (unit 1)
        )
      )
    )
  )

  (symbol (lib_id "antmicroResistors0402:R_47k_0402") (at 147.32 228.6 270) (unit 1)
    (in_bom yes) (on_board yes) (dnp no)
    (property "Reference" "R63" (at 148.59 223.52 0)
      (effects (font (size 1.524 1.524)) (justify left))
    )
    (property "Value" "R_47k_0402" (at 143.51 228.6 0)
      (effects (font (size 1.524 1.524)) hide)
    )
    (property "Footprint" "antmicro-footprints:R_0402_1005Metric" (at 152.4 233.68 0)
      (effects (font (size 1.524 1.524)) (justify left) hide)
    )
    (property "Datasheet" "https://www.bourns.com/docs/product-datasheets/cr.pdf" (at 147.32 228.6 0)
      (effects (font (size 1.27 1.27)) hide)
    )
    (property "Manufacturer" "Bourns" (at 157.48 233.68 0)
      (effects (font (size 1.524 1.524)) (justify left) hide)
    )
    (property "MPN" "CR0402-FX-4702GLF" (at 154.94 233.68 0)
      (effects (font (size 1.524 1.524)) (justify left) hide)
    )
    (property "Val" "47k" (at 148.59 233.68 0)
      (effects (font (size 1.27 1.27)) (justify left))
    )
    (property "License" "Apache-2.0" (at 121.92 248.92 0)
      (effects (font (size 1.27 1.27) (thickness 0.15)) (justify left bottom) hide)
    )
    (property "Author" "Antmicro" (at 119.38 248.92 0)
      (effects (font (size 1.27 1.27) (thickness 0.15)) (justify left bottom) hide)
    )
    (property "Tolerance" "1%" (at 137.16 248.92 0)
      (effects (font (size 1.27 1.27)) (justify left bottom) hide)
    )
    (property "Public" "False" (at 116.84 248.92 0)
      (effects (font (size 1.27 1.27)) (justify left bottom) hide)
    )
    (pin "1")
    (pin "2")
    (instances
      (project "ecp5-dc-scm"
        (path ""
          (reference "R63") (unit 1)
        )
      )
    )
  )

  (symbol (lib_id "antmicroResistors0402:R_47k_0402") (at 151.13 228.6 270) (unit 1)
    (in_bom yes) (on_board yes) (dnp no)
    (property "Reference" "R64" (at 152.4 223.52 0)
      (effects (font (size 1.524 1.524)) (justify left))
    )
    (property "Value" "R_47k_0402" (at 147.32 228.6 0)
      (effects (font (size 1.524 1.524)) hide)
    )
    (property "Footprint" "antmicro-footprints:R_0402_1005Metric" (at 156.21 233.68 0)
      (effects (font (size 1.524 1.524)) (justify left) hide)
    )
    (property "Datasheet" "https://www.bourns.com/docs/product-datasheets/cr.pdf" (at 151.13 228.6 0)
      (effects (font (size 1.27 1.27)) hide)
    )
    (property "Manufacturer" "Bourns" (at 161.29 233.68 0)
      (effects (font (size 1.524 1.524)) (justify left) hide)
    )
    (property "MPN" "CR0402-FX-4702GLF" (at 158.75 233.68 0)
      (effects (font (size 1.524 1.524)) (justify left) hide)
    )
    (property "Val" "47k" (at 152.4 233.68 0)
      (effects (font (size 1.27 1.27)) (justify left))
    )
    (property "License" "Apache-2.0" (at 125.73 248.92 0)
      (effects (font (size 1.27 1.27) (thickness 0.15)) (justify left bottom) hide)
    )
    (property "Author" "Antmicro" (at 123.19 248.92 0)
      (effects (font (size 1.27 1.27) (thickness 0.15)) (justify left bottom) hide)
    )
    (property "Tolerance" "1%" (at 140.97 248.92 0)
      (effects (font (size 1.27 1.27)) (justify left bottom) hide)
    )
    (property "Public" "False" (at 120.65 248.92 0)
      (effects (font (size 1.27 1.27)) (justify left bottom) hide)
    )
    (pin "1")
    (pin "2")
    (instances
      (project "ecp5-dc-scm"
        (path ""
          (reference "R64") (unit 1)
        )
      )
    )
  )

  (symbol (lib_id "antmicroResistors0402:R_47k_0402") (at 156.21 228.6 270) (unit 1)
    (in_bom yes) (on_board yes) (dnp no)
    (property "Reference" "R65" (at 157.48 223.52 0)
      (effects (font (size 1.524 1.524)) (justify left))
    )
    (property "Value" "R_47k_0402" (at 152.4 228.6 0)
      (effects (font (size 1.524 1.524)) hide)
    )
    (property "Footprint" "antmicro-footprints:R_0402_1005Metric" (at 161.29 233.68 0)
      (effects (font (size 1.524 1.524)) (justify left) hide)
    )
    (property "Datasheet" "https://www.bourns.com/docs/product-datasheets/cr.pdf" (at 156.21 228.6 0)
      (effects (font (size 1.27 1.27)) hide)
    )
    (property "Manufacturer" "Bourns" (at 166.37 233.68 0)
      (effects (font (size 1.524 1.524)) (justify left) hide)
    )
    (property "MPN" "CR0402-FX-4702GLF" (at 163.83 233.68 0)
      (effects (font (size 1.524 1.524)) (justify left) hide)
    )
    (property "Val" "47k" (at 157.48 233.68 0)
      (effects (font (size 1.27 1.27)) (justify left))
    )
    (property "License" "Apache-2.0" (at 130.81 248.92 0)
      (effects (font (size 1.27 1.27) (thickness 0.15)) (justify left bottom) hide)
    )
    (property "Author" "Antmicro" (at 128.27 248.92 0)
      (effects (font (size 1.27 1.27) (thickness 0.15)) (justify left bottom) hide)
    )
    (property "Tolerance" "1%" (at 146.05 248.92 0)
      (effects (font (size 1.27 1.27)) (justify left bottom) hide)
    )
    (property "Public" "False" (at 125.73 248.92 0)
      (effects (font (size 1.27 1.27)) (justify left bottom) hide)
    )
    (pin "1")
    (pin "2")
    (instances
      (project "ecp5-dc-scm"
        (path ""
          (reference "R65") (unit 1)
        )
      )
    )
  )

  (symbol (lib_id "antmicroResistors0402:R_47k_0402") (at 160.02 228.6 270) (unit 1)
    (in_bom yes) (on_board yes) (dnp no)
    (property "Reference" "R66" (at 161.29 223.52 0)
      (effects (font (size 1.524 1.524)) (justify left))
    )
    (property "Value" "R_47k_0402" (at 156.21 228.6 0)
      (effects (font (size 1.524 1.524)) hide)
    )
    (property "Footprint" "antmicro-footprints:R_0402_1005Metric" (at 165.1 233.68 0)
      (effects (font (size 1.524 1.524)) (justify left) hide)
    )
    (property "Datasheet" "https://www.bourns.com/docs/product-datasheets/cr.pdf" (at 160.02 228.6 0)
      (effects (font (size 1.27 1.27)) hide)
    )
    (property "Manufacturer" "Bourns" (at 170.18 233.68 0)
      (effects (font (size 1.524 1.524)) (justify left) hide)
    )
    (property "MPN" "CR0402-FX-4702GLF" (at 167.64 233.68 0)
      (effects (font (size 1.524 1.524)) (justify left) hide)
    )
    (property "Val" "47k" (at 161.29 233.68 0)
      (effects (font (size 1.27 1.27)) (justify left))
    )
    (property "License" "Apache-2.0" (at 134.62 248.92 0)
      (effects (font (size 1.27 1.27) (thickness 0.15)) (justify left bottom) hide)
    )
    (property "Author" "Antmicro" (at 132.08 248.92 0)
      (effects (font (size 1.27 1.27) (thickness 0.15)) (justify left bottom) hide)
    )
    (property "Tolerance" "1%" (at 149.86 248.92 0)
      (effects (font (size 1.27 1.27)) (justify left bottom) hide)
    )
    (property "Public" "False" (at 129.54 248.92 0)
      (effects (font (size 1.27 1.27)) (justify left bottom) hide)
    )
    (pin "1")
    (pin "2")
    (instances
      (project "ecp5-dc-scm"
        (path ""
          (reference "R66") (unit 1)
        )
      )
    )
  )

  (symbol (lib_id "antmicroResistors0402:R_47k_0402") (at 165.1 228.6 270) (unit 1)
    (in_bom yes) (on_board yes) (dnp no)
    (property "Reference" "R67" (at 166.37 223.52 0)
      (effects (font (size 1.524 1.524)) (justify left))
    )
    (property "Value" "R_47k_0402" (at 161.29 228.6 0)
      (effects (font (size 1.524 1.524)) hide)
    )
    (property "Footprint" "antmicro-footprints:R_0402_1005Metric" (at 170.18 233.68 0)
      (effects (font (size 1.524 1.524)) (justify left) hide)
    )
    (property "Datasheet" "https://www.bourns.com/docs/product-datasheets/cr.pdf" (at 165.1 228.6 0)
      (effects (font (size 1.27 1.27)) hide)
    )
    (property "Manufacturer" "Bourns" (at 175.26 233.68 0)
      (effects (font (size 1.524 1.524)) (justify left) hide)
    )
    (property "MPN" "CR0402-FX-4702GLF" (at 172.72 233.68 0)
      (effects (font (size 1.524 1.524)) (justify left) hide)
    )
    (property "Val" "47k" (at 166.37 233.68 0)
      (effects (font (size 1.27 1.27)) (justify left))
    )
    (property "License" "Apache-2.0" (at 139.7 248.92 0)
      (effects (font (size 1.27 1.27) (thickness 0.15)) (justify left bottom) hide)
    )
    (property "Author" "Antmicro" (at 137.16 248.92 0)
      (effects (font (size 1.27 1.27) (thickness 0.15)) (justify left bottom) hide)
    )
    (property "Tolerance" "1%" (at 154.94 248.92 0)
      (effects (font (size 1.27 1.27)) (justify left bottom) hide)
    )
    (property "Public" "False" (at 134.62 248.92 0)
      (effects (font (size 1.27 1.27)) (justify left bottom) hide)
    )
    (pin "1")
    (pin "2")
    (instances
      (project "ecp5-dc-scm"
        (path ""
          (reference "R67") (unit 1)
        )
      )
    )
  )

  (symbol (lib_id "antmicroResistors0402:R_47k_0402") (at 168.91 228.6 270) (unit 1)
    (in_bom yes) (on_board yes) (dnp no)
    (property "Reference" "R68" (at 170.18 223.52 0)
      (effects (font (size 1.524 1.524)) (justify left))
    )
    (property "Value" "R_47k_0402" (at 165.1 228.6 0)
      (effects (font (size 1.524 1.524)) hide)
    )
    (property "Footprint" "antmicro-footprints:R_0402_1005Metric" (at 173.99 233.68 0)
      (effects (font (size 1.524 1.524)) (justify left) hide)
    )
    (property "Datasheet" "https://www.bourns.com/docs/product-datasheets/cr.pdf" (at 168.91 228.6 0)
      (effects (font (size 1.27 1.27)) hide)
    )
    (property "Manufacturer" "Bourns" (at 179.07 233.68 0)
      (effects (font (size 1.524 1.524)) (justify left) hide)
    )
    (property "MPN" "CR0402-FX-4702GLF" (at 176.53 233.68 0)
      (effects (font (size 1.524 1.524)) (justify left) hide)
    )
    (property "Val" "47k" (at 170.18 233.68 0)
      (effects (font (size 1.27 1.27)) (justify left))
    )
    (property "License" "Apache-2.0" (at 143.51 248.92 0)
      (effects (font (size 1.27 1.27) (thickness 0.15)) (justify left bottom) hide)
    )
    (property "Author" "Antmicro" (at 140.97 248.92 0)
      (effects (font (size 1.27 1.27) (thickness 0.15)) (justify left bottom) hide)
    )
    (property "Tolerance" "1%" (at 158.75 248.92 0)
      (effects (font (size 1.27 1.27)) (justify left bottom) hide)
    )
    (property "Public" "False" (at 138.43 248.92 0)
      (effects (font (size 1.27 1.27)) (justify left bottom) hide)
    )
    (pin "1")
    (pin "2")
    (instances
      (project "ecp5-dc-scm"
        (path ""
          (reference "R68") (unit 1)
        )
      )
    )
  )

  (symbol (lib_id "antmicroResistors0402:R_10k_0402") (at 250.19 124.46 270) (unit 1)
    (in_bom yes) (on_board yes) (dnp no) (fields_autoplaced)
    (property "Reference" "R151" (at 252.73 125.73 90)
      (effects (font (size 1.524 1.524)) (justify left))
    )
    (property "Value" "R_10k_0402" (at 246.38 124.46 0)
      (effects (font (size 1.524 1.524)) hide)
    )
    (property "Footprint" "antmicro-footprints:R_0402_1005Metric" (at 255.27 129.54 0)
      (effects (font (size 1.524 1.524)) (justify left) hide)
    )
    (property "Datasheet" "https://www.bourns.com/docs/product-datasheets/cr.pdf" (at 250.19 124.46 0)
      (effects (font (size 1.27 1.27)) hide)
    )
    (property "Manufacturer" "Bourns" (at 260.35 129.54 0)
      (effects (font (size 1.524 1.524)) (justify left) hide)
    )
    (property "MPN" "CR0402-FX-1002GLF" (at 257.81 129.54 0)
      (effects (font (size 1.524 1.524)) (justify left) hide)
    )
    (property "Val" "10k" (at 252.73 128.27 90)
      (effects (font (size 1.27 1.27)) (justify left))
    )
    (property "License" "Apache-2.0" (at 224.79 144.78 0)
      (effects (font (size 1.27 1.27) (thickness 0.15)) (justify left bottom) hide)
    )
    (property "Author" "Antmicro" (at 222.25 144.78 0)
      (effects (font (size 1.27 1.27) (thickness 0.15)) (justify left bottom) hide)
    )
    (property "Tolerance" "1%" (at 240.03 144.78 0)
      (effects (font (size 1.27 1.27)) (justify left bottom) hide)
    )
    (property "Public" "False" (at 219.71 144.78 0)
      (effects (font (size 1.27 1.27)) (justify left bottom) hide)
    )
    (pin "1")
    (pin "2")
    (instances
      (project "ecp5-dc-scm"
        (path ""
          (reference "R151") (unit 1)
        )
      )
    )
  )

  (symbol (lib_id "antmicroResistors0402:R_4k7_0402") (at 250.19 113.03 270) (unit 1)
    (in_bom yes) (on_board yes) (dnp no) (fields_autoplaced)
    (property "Reference" "R150" (at 252.73 114.3 90)
      (effects (font (size 1.524 1.524)) (justify left))
    )
    (property "Value" "R_4k7_0402" (at 246.38 113.03 0)
      (effects (font (size 1.524 1.524)) hide)
    )
    (property "Footprint" "antmicro-footprints:R_0402_1005Metric" (at 255.27 118.11 0)
      (effects (font (size 1.524 1.524)) (justify left) hide)
    )
    (property "Datasheet" "https://www.bourns.com/docs/product-datasheets/cr.pdf" (at 250.19 113.03 0)
      (effects (font (size 1.27 1.27)) hide)
    )
    (property "Manufacturer" "Bourns" (at 260.35 118.11 0)
      (effects (font (size 1.524 1.524)) (justify left) hide)
    )
    (property "MPN" "CR0402-FX-4701GLF" (at 257.81 118.11 0)
      (effects (font (size 1.524 1.524)) (justify left) hide)
    )
    (property "Val" "4k7" (at 252.73 116.84 90)
      (effects (font (size 1.27 1.27)) (justify left))
    )
    (property "License" "Apache-2.0" (at 224.79 133.35 0)
      (effects (font (size 1.27 1.27) (thickness 0.15)) (justify left bottom) hide)
    )
    (property "Author" "Antmicro" (at 222.25 133.35 0)
      (effects (font (size 1.27 1.27) (thickness 0.15)) (justify left bottom) hide)
    )
    (property "Tolerance" "1%" (at 240.03 133.35 0)
      (effects (font (size 1.27 1.27)) (justify left bottom) hide)
    )
    (property "Public" "False" (at 219.71 133.35 0)
      (effects (font (size 1.27 1.27)) (justify left bottom) hide)
    )
    (pin "1")
    (pin "2")
    (instances
      (project "ecp5-dc-scm"
        (path ""
          (reference "R150") (unit 1)
        )
      )
    )
  )

  (symbol (lib_id "antmicroTVSDiodes:SP3011-06UTG") (at 375.92 237.49 90) (mirror x) (unit 1)
    (in_bom yes) (on_board yes) (dnp no)
    (property "Reference" "D2" (at 383.54 248.92 90)
      (effects (font (size 1.27 1.27)))
    )
    (property "Value" "SP3011-06UTG" (at 390.6012 240.7666 90)
      (effects (font (size 1.27 1.27)) (justify right) hide)
    )
    (property "Footprint" "antmicro-footprints:USON-14_3.5x1.35_P0.5mm" (at 369.57 267.97 0)
      (effects (font (size 1.27 1.27)) hide)
    )
    (property "Datasheet" "https://www.littelfuse.com/media?resourcetype=datasheets&itemid=c9002a97-9994-449b-b722-f45ab5538c7f&filename=littelfuse-tvs-diode-array-sp3011-datasheet" (at 367.03 275.59 0)
      (effects (font (size 1.27 1.27)) hide)
    )
    (property "MPN" "SP3011-06UTG" (at 383.54 251.46 90)
      (effects (font (size 1.27 1.27)))
    )
    (property "Manufacturer" "Littelfuse" (at 390.6012 236.1438 90)
      (effects (font (size 1.27 1.27)) (justify right) hide)
    )
    (property "Author" "Antmicro" (at 394.97 251.46 0)
      (effects (font (size 1.27 1.27) (thickness 0.15)) (justify left bottom) hide)
    )
    (property "License" "Apache-2.0" (at 397.51 251.46 0)
      (effects (font (size 1.27 1.27) (thickness 0.15)) (justify left bottom) hide)
    )
    (pin "10")
    (pin "11")
    (pin "12")
    (pin "13")
    (pin "14")
    (pin "8")
    (pin "9")
    (pin "2")
    (pin "3")
    (pin "4")
    (pin "5")
    (pin "6")
    (pin "7")
    (pin "1")
    (instances
      (project "ecp5-dc-scm"
        (path ""
          (reference "D2") (unit 1)
        )
      )
    )
  )

  (symbol (lib_id "antmicropower:GND") (at 250.19 132.08 0) (unit 1)
    (in_bom yes) (on_board yes) (dnp no)
    (property "Reference" "#PWR0147" (at 250.19 138.43 0)
      (effects (font (size 1.27 1.27)) hide)
    )
    (property "Value" "GND" (at 250.317 136.4742 0)
      (effects (font (size 1.27 1.27)))
    )
    (property "Footprint" "" (at 250.19 132.08 0)
      (effects (font (size 1.27 1.27)) hide)
    )
    (property "Datasheet" "" (at 250.19 132.08 0)
      (effects (font (size 1.27 1.27)) hide)
    )
    (property "Author" "Antmicro" (at 259.08 139.7 0)
      (effects (font (size 1.27 1.27) (thickness 0.15)) (justify left bottom) hide)
    )
    (property "License" "Apache-2.0" (at 259.08 142.24 0)
      (effects (font (size 1.27 1.27) (thickness 0.15)) (justify left bottom) hide)
    )
    (pin "1")
    (instances
      (project "ecp5-dc-scm"
        (path ""
          (reference "#PWR0147") (unit 1)
        )
      )
    )
  )

  (symbol (lib_id "antmicroUSBConnectors:USB-Micro-B_Amphenol_10118192-0001LF") (at 40.64 31.75 0) (unit 1)
    (in_bom yes) (on_board yes) (dnp no)
    (property "Reference" "J6" (at 28.575 24.13 0)
      (effects (font (size 1.524 1.524)))
    )
    (property "Value" "USB-Micro-B_Amphenol_10118192-0001LF" (at 45.085 26.67 0)
      (effects (font (size 1.524 1.524)))
    )
    (property "Footprint" "antmicro-footprints:USB-Micro-B_Receptacle_Amphenol_10118192" (at 45.72 26.67 0)
      (effects (font (size 1.524 1.524)) (justify left) hide)
    )
    (property "Datasheet" "http://www.amphenol-icc.com/media/wysiwyg/files/drawing/10118192.pdf" (at 45.72 24.13 0)
      (effects (font (size 1.524 1.524)) (justify left) hide)
    )
    (property "MPN" "10118192-0001LF" (at 45.72 19.05 0)
      (effects (font (size 1.524 1.524)) (justify left) hide)
    )
    (property "Manufacturer" "Amphenol" (at 45.72 3.81 0)
      (effects (font (size 1.524 1.524)) (justify left) hide)
    )
    (property "Author" "Antmicro" (at 73.66 52.07 0)
      (effects (font (size 1.27 1.27) (thickness 0.15)) (justify left bottom) hide)
    )
    (property "License" "Apache-2.0" (at 73.66 54.61 0)
      (effects (font (size 1.27 1.27) (thickness 0.15)) (justify left bottom) hide)
    )
    (pin "1")
    (pin "2")
    (pin "3")
    (pin "4")
    (pin "5")
    (pin "SH")
    (instances
      (project "ecp5-dc-scm"
        (path ""
          (reference "J6") (unit 1)
        )
      )
    )
  )

  (symbol (lib_id "antmicroGenericPinHeaders:PinHeader_2x7_P2mm_Drill1mm_Shrouded") (at 358.14 219.71 0) (unit 1)
    (in_bom yes) (on_board yes) (dnp no) (fields_autoplaced)
    (property "Reference" "J9" (at 363.22 213.36 0)
      (effects (font (size 1.27 1.27)))
    )
    (property "Value" "PinHeader_2x7_P2mm_Drill1mm_Shrouded" (at 363.22 215.9 0)
      (effects (font (size 1.27 1.27)))
    )
    (property "Footprint" "antmicro-footprints:PinHeader_2x7_P2mm_Drill1mm_Shrouded" (at 363.22 214.63 0)
      (effects (font (size 1.524 1.524)) (justify left) hide)
    )
    (property "Datasheet" "https://www.molex.com/pdm_docs/sd/878322620_sd.pdf" (at 363.22 212.09 0)
      (effects (font (size 1.524 1.524)) (justify left) hide)
    )
    (property "MPN" "0878311420" (at 363.22 207.01 0)
      (effects (font (size 1.524 1.524)) (justify left) hide)
    )
    (property "Manufacturer" "Molex" (at 363.22 191.77 0)
      (effects (font (size 1.524 1.524)) (justify left) hide)
    )
    (property "Author" "Antmicro" (at 383.54 237.49 0)
      (effects (font (size 1.27 1.27) (thickness 0.15)) (justify left bottom) hide)
    )
    (property "License" "Apache-2.0" (at 383.54 240.03 0)
      (effects (font (size 1.27 1.27) (thickness 0.15)) (justify left bottom) hide)
    )
    (pin "1")
    (pin "10")
    (pin "11")
    (pin "12")
    (pin "13")
    (pin "14")
    (pin "2")
    (pin "3")
    (pin "4")
    (pin "5")
    (pin "6")
    (pin "7")
    (pin "8")
    (pin "9")
    (instances
      (project "ecp5-dc-scm"
        (path ""
          (reference "J9") (unit 1)
        )
      )
    )
  )

  (symbol (lib_id "antmicroCapacitors0603:C_3u3_0603") (at 132.08 34.29 90) (unit 1)
    (in_bom yes) (on_board yes) (dnp no)
    (property "Reference" "C257" (at 125.73 29.21 90)
      (effects (font (size 1.524 1.524)) (justify right))
    )
    (property "Value" "C_3u3_0603" (at 135.89 34.29 0)
      (effects (font (size 1.524 1.524)) hide)
    )
    (property "Footprint" "antmicro-footprints:C_0603_1608Metric" (at 127 29.21 0)
      (effects (font (size 1.524 1.524)) (justify left) hide)
    )
    (property "Datasheet" "https://www.kemet.com/en/us/capacitors/product/C0603C335M9PACTU.html" (at 132.08 34.29 0)
      (effects (font (size 1.27 1.27)) hide)
    )
    (property "Manufacturer" "KEMET" (at 121.92 29.21 0)
      (effects (font (size 1.524 1.524)) (justify left) hide)
    )
    (property "MPN" "C0603C335M9PACTU" (at 124.46 29.21 0)
      (effects (font (size 1.524 1.524)) (justify left) hide)
    )
    (property "Val" "3u3" (at 128.27 34.29 90)
      (effects (font (size 1.27 1.27)) (justify right))
    )
    (property "License" "Apache-2.0" (at 154.94 13.97 0)
      (effects (font (size 1.27 1.27) (thickness 0.15)) (justify left bottom) hide)
    )
    (property "Author" "Antmicro" (at 157.48 13.97 0)
      (effects (font (size 1.27 1.27) (thickness 0.15)) (justify left bottom) hide)
    )
    (property "Voltage" "" (at 160.02 13.97 0)
      (effects (font (size 1.27 1.27)) (justify left bottom) hide)
    )
    (property "Dielectric" "" (at 162.56 13.97 0)
      (effects (font (size 1.27 1.27)) (justify left bottom) hide)
    )
    (property "Public" "False" (at 165.1 13.97 0)
      (effects (font (size 1.27 1.27)) (justify left bottom) hide)
    )
    (pin "1")
    (pin "2")
    (instances
      (project "ecp5-dc-scm"
        (path ""
          (reference "C257") (unit 1)
        )
      )
    )
  )

  (symbol (lib_id "antmicroCapacitors0402:C_100n_0402") (at 115.57 34.29 90) (unit 1)
    (in_bom yes) (on_board yes) (dnp no)
    (property "Reference" "C259" (at 114.3 29.21 90)
      (effects (font (size 1.524 1.524)) (justify left))
    )
    (property "Value" "C_100n_0402" (at 119.38 34.29 0)
      (effects (font (size 1.524 1.524)) hide)
    )
    (property "Footprint" "antmicro-footprints:C_0402_1005Metric" (at 110.49 29.21 0)
      (effects (font (size 1.524 1.524)) (justify left) hide)
    )
    (property "Datasheet" "https://www.murata.com/products/productdetail?partno=GRM155R61H104KE14%23" (at 115.57 34.29 0)
      (effects (font (size 1.27 1.27)) hide)
    )
    (property "Manufacturer" "Murata" (at 105.41 29.21 0)
      (effects (font (size 1.524 1.524)) (justify left) hide)
    )
    (property "MPN" "GRM155R61H104KE14D" (at 107.95 29.21 0)
      (effects (font (size 1.524 1.524)) (justify left) hide)
    )
    (property "Val" "100n" (at 114.3 34.29 90)
      (effects (font (size 1.27 1.27)) (justify left))
    )
    (property "License" "Apache-2.0" (at 138.43 13.97 0)
      (effects (font (size 1.27 1.27) (thickness 0.15)) (justify left bottom) hide)
    )
    (property "Author" "Antmicro" (at 140.97 13.97 0)
      (effects (font (size 1.27 1.27) (thickness 0.15)) (justify left bottom) hide)
    )
    (property "Voltage" "50V" (at 143.51 13.97 0)
      (effects (font (size 1.27 1.27)) (justify left bottom) hide)
    )
    (property "Dielectric" "X5R" (at 146.05 13.97 0)
      (effects (font (size 1.27 1.27)) (justify left bottom) hide)
    )
    (property "Public" "False" (at 148.59 13.97 0)
      (effects (font (size 1.27 1.27)) (justify left bottom) hide)
    )
    (pin "1")
    (pin "2")
    (instances
      (project "ecp5-dc-scm"
        (path ""
          (reference "C259") (unit 1)
        )
      )
    )
  )

  (symbol (lib_id "antmicropower:GND") (at 115.57 36.83 0) (unit 1)
    (in_bom yes) (on_board yes) (dnp no)
    (property "Reference" "#PWR0153" (at 115.57 43.18 0)
      (effects (font (size 1.27 1.27)) hide)
    )
    (property "Value" "GND" (at 115.697 41.2242 0)
      (effects (font (size 1.27 1.27)))
    )
    (property "Footprint" "" (at 115.57 36.83 0)
      (effects (font (size 1.27 1.27)) hide)
    )
    (property "Datasheet" "" (at 115.57 36.83 0)
      (effects (font (size 1.27 1.27)) hide)
    )
    (property "Author" "Antmicro" (at 124.46 44.45 0)
      (effects (font (size 1.27 1.27) (thickness 0.15)) (justify left bottom) hide)
    )
    (property "License" "Apache-2.0" (at 124.46 46.99 0)
      (effects (font (size 1.27 1.27) (thickness 0.15)) (justify left bottom) hide)
    )
    (pin "1")
    (instances
      (project "ecp5-dc-scm"
        (path ""
          (reference "#PWR0153") (unit 1)
        )
      )
    )
  )

  (symbol (lib_id "antmicroCapacitors0402:C_100n_0402") (at 66.04 273.05 90) (unit 1)
    (in_bom yes) (on_board yes) (dnp no)
    (property "Reference" "C246" (at 64.77 262.89 0)
      (effects (font (size 1.524 1.524)) (justify right))
    )
    (property "Value" "C_100n_0402" (at 69.85 273.05 0)
      (effects (font (size 1.524 1.524)) hide)
    )
    (property "Footprint" "antmicro-footprints:C_0402_1005Metric" (at 60.96 267.97 0)
      (effects (font (size 1.524 1.524)) (justify left) hide)
    )
    (property "Datasheet" "https://www.murata.com/products/productdetail?partno=GRM155R61H104KE14%23" (at 66.04 273.05 0)
      (effects (font (size 1.27 1.27)) hide)
    )
    (property "Manufacturer" "Murata" (at 55.88 267.97 0)
      (effects (font (size 1.524 1.524)) (justify left) hide)
    )
    (property "MPN" "GRM155R61H104KE14D" (at 58.42 267.97 0)
      (effects (font (size 1.524 1.524)) (justify left) hide)
    )
    (property "Val" "100n" (at 64.77 271.78 0)
      (effects (font (size 1.27 1.27)) (justify right))
    )
    (property "License" "Apache-2.0" (at 88.9 252.73 0)
      (effects (font (size 1.27 1.27) (thickness 0.15)) (justify left bottom) hide)
    )
    (property "Author" "Antmicro" (at 91.44 252.73 0)
      (effects (font (size 1.27 1.27) (thickness 0.15)) (justify left bottom) hide)
    )
    (property "Voltage" "50V" (at 93.98 252.73 0)
      (effects (font (size 1.27 1.27)) (justify left bottom) hide)
    )
    (property "Dielectric" "X5R" (at 96.52 252.73 0)
      (effects (font (size 1.27 1.27)) (justify left bottom) hide)
    )
    (property "Public" "False" (at 99.06 252.73 0)
      (effects (font (size 1.27 1.27)) (justify left bottom) hide)
    )
    (pin "1")
    (pin "2")
    (instances
      (project "ecp5-dc-scm"
        (path ""
          (reference "C246") (unit 1)
        )
      )
    )
  )

  (symbol (lib_id "antmicroCapacitors0402:C_100n_0402") (at 72.39 273.05 90) (unit 1)
    (in_bom yes) (on_board yes) (dnp no)
    (property "Reference" "C247" (at 71.12 262.89 0)
      (effects (font (size 1.524 1.524)) (justify right))
    )
    (property "Value" "C_100n_0402" (at 76.2 273.05 0)
      (effects (font (size 1.524 1.524)) hide)
    )
    (property "Footprint" "antmicro-footprints:C_0402_1005Metric" (at 67.31 267.97 0)
      (effects (font (size 1.524 1.524)) (justify left) hide)
    )
    (property "Datasheet" "https://www.murata.com/products/productdetail?partno=GRM155R61H104KE14%23" (at 72.39 273.05 0)
      (effects (font (size 1.27 1.27)) hide)
    )
    (property "Manufacturer" "Murata" (at 62.23 267.97 0)
      (effects (font (size 1.524 1.524)) (justify left) hide)
    )
    (property "MPN" "GRM155R61H104KE14D" (at 64.77 267.97 0)
      (effects (font (size 1.524 1.524)) (justify left) hide)
    )
    (property "Val" "100n" (at 71.12 271.78 0)
      (effects (font (size 1.27 1.27)) (justify right))
    )
    (property "License" "Apache-2.0" (at 95.25 252.73 0)
      (effects (font (size 1.27 1.27) (thickness 0.15)) (justify left bottom) hide)
    )
    (property "Author" "Antmicro" (at 97.79 252.73 0)
      (effects (font (size 1.27 1.27) (thickness 0.15)) (justify left bottom) hide)
    )
    (property "Voltage" "50V" (at 100.33 252.73 0)
      (effects (font (size 1.27 1.27)) (justify left bottom) hide)
    )
    (property "Dielectric" "X5R" (at 102.87 252.73 0)
      (effects (font (size 1.27 1.27)) (justify left bottom) hide)
    )
    (property "Public" "False" (at 105.41 252.73 0)
      (effects (font (size 1.27 1.27)) (justify left bottom) hide)
    )
    (pin "1")
    (pin "2")
    (instances
      (project "ecp5-dc-scm"
        (path ""
          (reference "C247") (unit 1)
        )
      )
    )
  )

  (symbol (lib_id "antmicropower:GND") (at 72.39 278.13 0) (mirror y) (unit 1)
    (in_bom yes) (on_board yes) (dnp no)
    (property "Reference" "#PWR0129" (at 72.39 284.48 0)
      (effects (font (size 1.27 1.27)) hide)
    )
    (property "Value" "GND" (at 72.263 282.5242 0)
      (effects (font (size 1.27 1.27)))
    )
    (property "Footprint" "" (at 72.39 278.13 0)
      (effects (font (size 1.27 1.27)) hide)
    )
    (property "Datasheet" "" (at 72.39 278.13 0)
      (effects (font (size 1.27 1.27)) hide)
    )
    (property "Author" "Antmicro" (at 63.5 285.75 0)
      (effects (font (size 1.27 1.27) (thickness 0.15)) (justify left bottom) hide)
    )
    (property "License" "Apache-2.0" (at 63.5 288.29 0)
      (effects (font (size 1.27 1.27) (thickness 0.15)) (justify left bottom) hide)
    )
    (pin "1")
    (instances
      (project "ecp5-dc-scm"
        (path ""
          (reference "#PWR0129") (unit 1)
        )
      )
    )
  )

  (symbol (lib_id "antmicroCapacitors0402:C_100n_0402") (at 53.34 273.05 90) (unit 1)
    (in_bom yes) (on_board yes) (dnp no)
    (property "Reference" "C244" (at 52.07 262.89 0)
      (effects (font (size 1.524 1.524)) (justify right))
    )
    (property "Value" "C_100n_0402" (at 57.15 273.05 0)
      (effects (font (size 1.524 1.524)) hide)
    )
    (property "Footprint" "antmicro-footprints:C_0402_1005Metric" (at 48.26 267.97 0)
      (effects (font (size 1.524 1.524)) (justify left) hide)
    )
    (property "Datasheet" "https://www.murata.com/products/productdetail?partno=GRM155R61H104KE14%23" (at 53.34 273.05 0)
      (effects (font (size 1.27 1.27)) hide)
    )
    (property "Manufacturer" "Murata" (at 43.18 267.97 0)
      (effects (font (size 1.524 1.524)) (justify left) hide)
    )
    (property "MPN" "GRM155R61H104KE14D" (at 45.72 267.97 0)
      (effects (font (size 1.524 1.524)) (justify left) hide)
    )
    (property "Val" "100n" (at 52.07 271.78 0)
      (effects (font (size 1.27 1.27)) (justify right))
    )
    (property "License" "Apache-2.0" (at 76.2 252.73 0)
      (effects (font (size 1.27 1.27) (thickness 0.15)) (justify left bottom) hide)
    )
    (property "Author" "Antmicro" (at 78.74 252.73 0)
      (effects (font (size 1.27 1.27) (thickness 0.15)) (justify left bottom) hide)
    )
    (property "Voltage" "50V" (at 81.28 252.73 0)
      (effects (font (size 1.27 1.27)) (justify left bottom) hide)
    )
    (property "Dielectric" "X5R" (at 83.82 252.73 0)
      (effects (font (size 1.27 1.27)) (justify left bottom) hide)
    )
    (property "Public" "False" (at 86.36 252.73 0)
      (effects (font (size 1.27 1.27)) (justify left bottom) hide)
    )
    (pin "1")
    (pin "2")
    (instances
      (project "ecp5-dc-scm"
        (path ""
          (reference "C244") (unit 1)
        )
      )
    )
  )

  (symbol (lib_id "antmicroCapacitors0402:C_100n_0402") (at 59.69 273.05 90) (unit 1)
    (in_bom yes) (on_board yes) (dnp no)
    (property "Reference" "C245" (at 58.42 262.89 0)
      (effects (font (size 1.524 1.524)) (justify right))
    )
    (property "Value" "C_100n_0402" (at 63.5 273.05 0)
      (effects (font (size 1.524 1.524)) hide)
    )
    (property "Footprint" "antmicro-footprints:C_0402_1005Metric" (at 54.61 267.97 0)
      (effects (font (size 1.524 1.524)) (justify left) hide)
    )
    (property "Datasheet" "https://www.murata.com/products/productdetail?partno=GRM155R61H104KE14%23" (at 59.69 273.05 0)
      (effects (font (size 1.27 1.27)) hide)
    )
    (property "Manufacturer" "Murata" (at 49.53 267.97 0)
      (effects (font (size 1.524 1.524)) (justify left) hide)
    )
    (property "MPN" "GRM155R61H104KE14D" (at 52.07 267.97 0)
      (effects (font (size 1.524 1.524)) (justify left) hide)
    )
    (property "Val" "100n" (at 58.42 271.78 0)
      (effects (font (size 1.27 1.27)) (justify right))
    )
    (property "License" "Apache-2.0" (at 82.55 252.73 0)
      (effects (font (size 1.27 1.27) (thickness 0.15)) (justify left bottom) hide)
    )
    (property "Author" "Antmicro" (at 85.09 252.73 0)
      (effects (font (size 1.27 1.27) (thickness 0.15)) (justify left bottom) hide)
    )
    (property "Voltage" "50V" (at 87.63 252.73 0)
      (effects (font (size 1.27 1.27)) (justify left bottom) hide)
    )
    (property "Dielectric" "X5R" (at 90.17 252.73 0)
      (effects (font (size 1.27 1.27)) (justify left bottom) hide)
    )
    (property "Public" "False" (at 92.71 252.73 0)
      (effects (font (size 1.27 1.27)) (justify left bottom) hide)
    )
    (pin "1")
    (pin "2")
    (instances
      (project "ecp5-dc-scm"
        (path ""
          (reference "C245") (unit 1)
        )
      )
    )
  )

  (symbol (lib_id "antmicroCapacitors0402:C_100n_0402") (at 40.64 273.05 90) (unit 1)
    (in_bom yes) (on_board yes) (dnp no)
    (property "Reference" "C242" (at 39.37 269.24 0)
      (effects (font (size 1.524 1.524)) (justify left))
    )
    (property "Value" "C_100n_0402" (at 44.45 273.05 0)
      (effects (font (size 1.524 1.524)) hide)
    )
    (property "Footprint" "antmicro-footprints:C_0402_1005Metric" (at 35.56 267.97 0)
      (effects (font (size 1.524 1.524)) (justify left) hide)
    )
    (property "Datasheet" "https://www.murata.com/products/productdetail?partno=GRM155R61H104KE14%23" (at 40.64 273.05 0)
      (effects (font (size 1.27 1.27)) hide)
    )
    (property "Manufacturer" "Murata" (at 30.48 267.97 0)
      (effects (font (size 1.524 1.524)) (justify left) hide)
    )
    (property "MPN" "GRM155R61H104KE14D" (at 33.02 267.97 0)
      (effects (font (size 1.524 1.524)) (justify left) hide)
    )
    (property "Val" "100n" (at 39.37 276.86 0)
      (effects (font (size 1.27 1.27)) (justify left))
    )
    (property "License" "Apache-2.0" (at 63.5 252.73 0)
      (effects (font (size 1.27 1.27) (thickness 0.15)) (justify left bottom) hide)
    )
    (property "Author" "Antmicro" (at 66.04 252.73 0)
      (effects (font (size 1.27 1.27) (thickness 0.15)) (justify left bottom) hide)
    )
    (property "Voltage" "50V" (at 68.58 252.73 0)
      (effects (font (size 1.27 1.27)) (justify left bottom) hide)
    )
    (property "Dielectric" "X5R" (at 71.12 252.73 0)
      (effects (font (size 1.27 1.27)) (justify left bottom) hide)
    )
    (property "Public" "False" (at 73.66 252.73 0)
      (effects (font (size 1.27 1.27)) (justify left bottom) hide)
    )
    (pin "1")
    (pin "2")
    (instances
      (project "ecp5-dc-scm"
        (path ""
          (reference "C242") (unit 1)
        )
      )
    )
  )

  (symbol (lib_id "antmicroCapacitors0402:C_100n_0402") (at 46.99 273.05 90) (unit 1)
    (in_bom yes) (on_board yes) (dnp no)
    (property "Reference" "C243" (at 45.72 262.89 0)
      (effects (font (size 1.524 1.524)) (justify right))
    )
    (property "Value" "C_100n_0402" (at 50.8 273.05 0)
      (effects (font (size 1.524 1.524)) hide)
    )
    (property "Footprint" "antmicro-footprints:C_0402_1005Metric" (at 41.91 267.97 0)
      (effects (font (size 1.524 1.524)) (justify left) hide)
    )
    (property "Datasheet" "https://www.murata.com/products/productdetail?partno=GRM155R61H104KE14%23" (at 46.99 273.05 0)
      (effects (font (size 1.27 1.27)) hide)
    )
    (property "Manufacturer" "Murata" (at 36.83 267.97 0)
      (effects (font (size 1.524 1.524)) (justify left) hide)
    )
    (property "MPN" "GRM155R61H104KE14D" (at 39.37 267.97 0)
      (effects (font (size 1.524 1.524)) (justify left) hide)
    )
    (property "Val" "100n" (at 45.72 271.78 0)
      (effects (font (size 1.27 1.27)) (justify right))
    )
    (property "License" "Apache-2.0" (at 69.85 252.73 0)
      (effects (font (size 1.27 1.27) (thickness 0.15)) (justify left bottom) hide)
    )
    (property "Author" "Antmicro" (at 72.39 252.73 0)
      (effects (font (size 1.27 1.27) (thickness 0.15)) (justify left bottom) hide)
    )
    (property "Voltage" "50V" (at 74.93 252.73 0)
      (effects (font (size 1.27 1.27)) (justify left bottom) hide)
    )
    (property "Dielectric" "X5R" (at 77.47 252.73 0)
      (effects (font (size 1.27 1.27)) (justify left bottom) hide)
    )
    (property "Public" "False" (at 80.01 252.73 0)
      (effects (font (size 1.27 1.27)) (justify left bottom) hide)
    )
    (pin "1")
    (pin "2")
    (instances
      (project "ecp5-dc-scm"
        (path ""
          (reference "C243") (unit 1)
        )
      )
    )
  )

  (symbol (lib_id "antmicroResistors0402:R_10k_0402") (at 166.37 78.74 90) (mirror x) (unit 1)
    (in_bom no) (on_board yes) (dnp yes) (fields_autoplaced)
    (property "Reference" "R147" (at 168.91 78.74 90)
      (effects (font (size 1.524 1.524)) (justify right))
    )
    (property "Value" "R_10k_0402" (at 170.18 78.74 0)
      (effects (font (size 1.524 1.524)) hide)
    )
    (property "Footprint" "antmicro-footprints:R_0402_1005Metric" (at 161.29 83.82 0)
      (effects (font (size 1.524 1.524)) (justify left) hide)
    )
    (property "Datasheet" "https://www.bourns.com/docs/product-datasheets/cr.pdf" (at 166.37 78.74 0)
      (effects (font (size 1.27 1.27)) hide)
    )
    (property "Manufacturer" "Bourns" (at 156.21 83.82 0)
      (effects (font (size 1.524 1.524)) (justify left) hide)
    )
    (property "MPN" "CR0402-FX-1002GLF" (at 158.75 83.82 0)
      (effects (font (size 1.524 1.524)) (justify left) hide)
    )
    (property "Val" "10k" (at 168.91 81.28 90)
      (effects (font (size 1.27 1.27)) (justify right))
    )
    (property "DNP" "DNP" (at 168.91 83.82 90)
      (effects (font (size 1.27 1.27)) (justify right))
    )
    (property "License" "Apache-2.0" (at 191.77 99.06 0)
      (effects (font (size 1.27 1.27) (thickness 0.15)) (justify left bottom) hide)
    )
    (property "Author" "Antmicro" (at 194.31 99.06 0)
      (effects (font (size 1.27 1.27) (thickness 0.15)) (justify left bottom) hide)
    )
    (property "Tolerance" "1%" (at 176.53 99.06 0)
      (effects (font (size 1.27 1.27)) (justify left bottom) hide)
    )
    (property "Public" "False" (at 196.85 99.06 0)
      (effects (font (size 1.27 1.27)) (justify left bottom) hide)
    )
    (pin "1")
    (pin "2")
    (instances
      (project "ecp5-dc-scm"
        (path ""
          (reference "R147") (unit 1)
        )
      )
    )
  )

  (symbol (lib_id "antmicroResistors0402:R_4k7_0402") (at 166.37 68.58 90) (mirror x) (unit 1)
    (in_bom no) (on_board yes) (dnp yes) (fields_autoplaced)
    (property "Reference" "R146" (at 163.83 69.85 90)
      (effects (font (size 1.524 1.524)) (justify left))
    )
    (property "Value" "R_4k7_0402" (at 170.18 68.58 0)
      (effects (font (size 1.524 1.524)) hide)
    )
    (property "Footprint" "antmicro-footprints:R_0402_1005Metric" (at 161.29 73.66 0)
      (effects (font (size 1.524 1.524)) (justify left) hide)
    )
    (property "Datasheet" "https://www.bourns.com/docs/product-datasheets/cr.pdf" (at 166.37 68.58 0)
      (effects (font (size 1.27 1.27)) hide)
    )
    (property "Manufacturer" "Bourns" (at 156.21 73.66 0)
      (effects (font (size 1.524 1.524)) (justify left) hide)
    )
    (property "MPN" "CR0402-FX-4701GLF" (at 158.75 73.66 0)
      (effects (font (size 1.524 1.524)) (justify left) hide)
    )
    (property "Val" "4k7" (at 163.83 72.39 90)
      (effects (font (size 1.27 1.27)) (justify left))
    )
    (property "DNP" "DNP" (at 169.545 68.58 90)
      (effects (font (size 1.27 1.27)))
    )
    (property "License" "Apache-2.0" (at 191.77 88.9 0)
      (effects (font (size 1.27 1.27) (thickness 0.15)) (justify left bottom) hide)
    )
    (property "Author" "Antmicro" (at 194.31 88.9 0)
      (effects (font (size 1.27 1.27) (thickness 0.15)) (justify left bottom) hide)
    )
    (property "Tolerance" "1%" (at 176.53 88.9 0)
      (effects (font (size 1.27 1.27)) (justify left bottom) hide)
    )
    (property "Public" "False" (at 196.85 88.9 0)
      (effects (font (size 1.27 1.27)) (justify left bottom) hide)
    )
    (pin "1")
    (pin "2")
    (instances
      (project "ecp5-dc-scm"
        (path ""
          (reference "R146") (unit 1)
        )
      )
    )
  )

  (symbol (lib_id "antmicropower:GND") (at 166.37 85.09 0) (mirror y) (unit 1)
    (in_bom yes) (on_board yes) (dnp no)
    (property "Reference" "#PWR0149" (at 166.37 91.44 0)
      (effects (font (size 1.27 1.27)) hide)
    )
    (property "Value" "GND" (at 166.243 89.4842 0)
      (effects (font (size 1.27 1.27)))
    )
    (property "Footprint" "" (at 166.37 85.09 0)
      (effects (font (size 1.27 1.27)) hide)
    )
    (property "Datasheet" "" (at 166.37 85.09 0)
      (effects (font (size 1.27 1.27)) hide)
    )
    (property "Author" "Antmicro" (at 157.48 92.71 0)
      (effects (font (size 1.27 1.27) (thickness 0.15)) (justify left bottom) hide)
    )
    (property "License" "Apache-2.0" (at 157.48 95.25 0)
      (effects (font (size 1.27 1.27) (thickness 0.15)) (justify left bottom) hide)
    )
    (pin "1")
    (instances
      (project "ecp5-dc-scm"
        (path ""
          (reference "#PWR0149") (unit 1)
        )
      )
    )
  )

  (symbol (lib_id "antmicropower:GND") (at 322.58 229.87 0) (unit 1)
    (in_bom yes) (on_board yes) (dnp no)
    (property "Reference" "#PWR037" (at 322.58 236.22 0)
      (effects (font (size 1.27 1.27)) hide)
    )
    (property "Value" "GND" (at 322.707 234.2642 0)
      (effects (font (size 1.27 1.27)))
    )
    (property "Footprint" "" (at 322.58 229.87 0)
      (effects (font (size 1.27 1.27)) hide)
    )
    (property "Datasheet" "" (at 322.58 229.87 0)
      (effects (font (size 1.27 1.27)) hide)
    )
    (property "Author" "Antmicro" (at 331.47 237.49 0)
      (effects (font (size 1.27 1.27) (thickness 0.15)) (justify left bottom) hide)
    )
    (property "License" "Apache-2.0" (at 331.47 240.03 0)
      (effects (font (size 1.27 1.27) (thickness 0.15)) (justify left bottom) hide)
    )
    (pin "1")
    (instances
      (project "ecp5-dc-scm"
        (path ""
          (reference "#PWR037") (unit 1)
        )
      )
    )
  )

  (symbol (lib_id "antmicroCapacitors0402:C_100n_0402") (at 146.05 189.23 90) (unit 1)
    (in_bom yes) (on_board yes) (dnp no) (fields_autoplaced)
    (property "Reference" "C248" (at 148.59 185.4136 90)
      (effects (font (size 1.524 1.524)) (justify right))
    )
    (property "Value" "C_100n_0402" (at 149.86 189.23 0)
      (effects (font (size 1.524 1.524)) hide)
    )
    (property "Footprint" "antmicro-footprints:C_0402_1005Metric" (at 140.97 184.15 0)
      (effects (font (size 1.524 1.524)) (justify left) hide)
    )
    (property "Datasheet" "https://www.murata.com/products/productdetail?partno=GRM155R61H104KE14%23" (at 146.05 189.23 0)
      (effects (font (size 1.27 1.27)) hide)
    )
    (property "Manufacturer" "Murata" (at 135.89 184.15 0)
      (effects (font (size 1.524 1.524)) (justify left) hide)
    )
    (property "MPN" "GRM155R61H104KE14D" (at 138.43 184.15 0)
      (effects (font (size 1.524 1.524)) (justify left) hide)
    )
    (property "Val" "100n" (at 148.59 187.9536 90)
      (effects (font (size 1.27 1.27)) (justify right))
    )
    (property "License" "Apache-2.0" (at 168.91 168.91 0)
      (effects (font (size 1.27 1.27) (thickness 0.15)) (justify left bottom) hide)
    )
    (property "Author" "Antmicro" (at 171.45 168.91 0)
      (effects (font (size 1.27 1.27) (thickness 0.15)) (justify left bottom) hide)
    )
    (property "Voltage" "50V" (at 173.99 168.91 0)
      (effects (font (size 1.27 1.27)) (justify left bottom) hide)
    )
    (property "Dielectric" "X5R" (at 176.53 168.91 0)
      (effects (font (size 1.27 1.27)) (justify left bottom) hide)
    )
    (property "Public" "False" (at 179.07 168.91 0)
      (effects (font (size 1.27 1.27)) (justify left bottom) hide)
    )
    (pin "1")
    (pin "2")
    (instances
      (project "ecp5-dc-scm"
        (path ""
          (reference "C248") (unit 1)
        )
      )
    )
  )

  (symbol (lib_id "antmicropower:GND") (at 146.05 191.77 0) (unit 1)
    (in_bom yes) (on_board yes) (dnp no)
    (property "Reference" "#PWR0131" (at 146.05 198.12 0)
      (effects (font (size 1.27 1.27)) hide)
    )
    (property "Value" "GND" (at 146.177 196.1642 0)
      (effects (font (size 1.27 1.27)))
    )
    (property "Footprint" "" (at 146.05 191.77 0)
      (effects (font (size 1.27 1.27)) hide)
    )
    (property "Datasheet" "" (at 146.05 191.77 0)
      (effects (font (size 1.27 1.27)) hide)
    )
    (property "Author" "Antmicro" (at 154.94 199.39 0)
      (effects (font (size 1.27 1.27) (thickness 0.15)) (justify left bottom) hide)
    )
    (property "License" "Apache-2.0" (at 154.94 201.93 0)
      (effects (font (size 1.27 1.27) (thickness 0.15)) (justify left bottom) hide)
    )
    (pin "1")
    (instances
      (project "ecp5-dc-scm"
        (path ""
          (reference "#PWR0131") (unit 1)
        )
      )
    )
  )

  (symbol (lib_id "antmicroGenericPinHeaders:PinHeader_1x6_P2.54mm_Drill1.1mm") (at 323.85 214.63 0) (unit 1)
    (in_bom yes) (on_board yes) (dnp no)
    (property "Reference" "J7" (at 330.2 214.63 0)
      (effects (font (size 1.27 1.27)) (justify left))
    )
    (property "Value" "PinHeader_1x6_P2.54mm_Drill1.1mm" (at 309.245 211.455 0)
      (effects (font (size 1.27 1.27)) (justify left))
    )
    (property "Footprint" "antmicro-footprints:PinHeader_1x6_P2.54mm_Drill1.1mm" (at 328.93 209.55 0)
      (effects (font (size 1.524 1.524)) (justify left) hide)
    )
    (property "Datasheet" "https://www.we-online.com/components/products/datasheet/61300611121.pdf" (at 328.93 207.01 0)
      (effects (font (size 1.524 1.524)) (justify left) hide)
    )
    (property "MPN" "61300611121" (at 322.58 204.47 0)
      (effects (font (size 1.524 1.524)) (justify left) hide)
    )
    (property "Manufacturer" "Würth Elektronik" (at 328.93 186.69 0)
      (effects (font (size 1.524 1.524)) (justify left) hide)
    )
    (property "Author" "Antmicro" (at 344.17 234.95 0)
      (effects (font (size 1.27 1.27) (thickness 0.15)) (justify left bottom) hide)
    )
    (property "License" "Apache-2.0" (at 344.17 237.49 0)
      (effects (font (size 1.27 1.27) (thickness 0.15)) (justify left bottom) hide)
    )
    (pin "1")
    (pin "2")
    (pin "3")
    (pin "4")
    (pin "5")
    (pin "6")
    (instances
      (project "ecp5-dc-scm"
        (path ""
          (reference "J7") (unit 1)
        )
      )
    )
  )

  (symbol (lib_id "antmicroCapacitors0402:C_100n_0402") (at 153.67 29.21 90) (unit 1)
    (in_bom yes) (on_board yes) (dnp no)
    (property "Reference" "C253" (at 152.4 24.13 90)
      (effects (font (size 1.524 1.524)) (justify left))
    )
    (property "Value" "C_100n_0402" (at 157.48 29.21 0)
      (effects (font (size 1.524 1.524)) hide)
    )
    (property "Footprint" "antmicro-footprints:C_0402_1005Metric" (at 148.59 24.13 0)
      (effects (font (size 1.524 1.524)) (justify left) hide)
    )
    (property "Datasheet" "https://www.murata.com/products/productdetail?partno=GRM155R61H104KE14%23" (at 153.67 29.21 0)
      (effects (font (size 1.27 1.27)) hide)
    )
    (property "Manufacturer" "Murata" (at 143.51 24.13 0)
      (effects (font (size 1.524 1.524)) (justify left) hide)
    )
    (property "MPN" "GRM155R61H104KE14D" (at 146.05 24.13 0)
      (effects (font (size 1.524 1.524)) (justify left) hide)
    )
    (property "Val" "100n" (at 152.4 29.21 90)
      (effects (font (size 1.27 1.27)) (justify left))
    )
    (property "License" "Apache-2.0" (at 176.53 8.89 0)
      (effects (font (size 1.27 1.27) (thickness 0.15)) (justify left bottom) hide)
    )
    (property "Author" "Antmicro" (at 179.07 8.89 0)
      (effects (font (size 1.27 1.27) (thickness 0.15)) (justify left bottom) hide)
    )
    (property "Voltage" "50V" (at 181.61 8.89 0)
      (effects (font (size 1.27 1.27)) (justify left bottom) hide)
    )
    (property "Dielectric" "X5R" (at 184.15 8.89 0)
      (effects (font (size 1.27 1.27)) (justify left bottom) hide)
    )
    (property "Public" "False" (at 186.69 8.89 0)
      (effects (font (size 1.27 1.27)) (justify left bottom) hide)
    )
    (pin "1")
    (pin "2")
    (instances
      (project "ecp5-dc-scm"
        (path ""
          (reference "C253") (unit 1)
        )
      )
    )
  )

  (symbol (lib_id "antmicroCapacitors0402:C_100n_0402") (at 161.29 29.21 90) (unit 1)
    (in_bom yes) (on_board yes) (dnp no)
    (property "Reference" "C254" (at 154.94 24.13 90)
      (effects (font (size 1.524 1.524)) (justify right))
    )
    (property "Value" "C_100n_0402" (at 165.1 29.21 0)
      (effects (font (size 1.524 1.524)) hide)
    )
    (property "Footprint" "antmicro-footprints:C_0402_1005Metric" (at 156.21 24.13 0)
      (effects (font (size 1.524 1.524)) (justify left) hide)
    )
    (property "Datasheet" "https://www.murata.com/products/productdetail?partno=GRM155R61H104KE14%23" (at 161.29 29.21 0)
      (effects (font (size 1.27 1.27)) hide)
    )
    (property "Manufacturer" "Murata" (at 151.13 24.13 0)
      (effects (font (size 1.524 1.524)) (justify left) hide)
    )
    (property "MPN" "GRM155R61H104KE14D" (at 153.67 24.13 0)
      (effects (font (size 1.524 1.524)) (justify left) hide)
    )
    (property "Val" "100n" (at 156.21 29.21 90)
      (effects (font (size 1.27 1.27)) (justify right))
    )
    (property "License" "Apache-2.0" (at 184.15 8.89 0)
      (effects (font (size 1.27 1.27) (thickness 0.15)) (justify left bottom) hide)
    )
    (property "Author" "Antmicro" (at 186.69 8.89 0)
      (effects (font (size 1.27 1.27) (thickness 0.15)) (justify left bottom) hide)
    )
    (property "Voltage" "50V" (at 189.23 8.89 0)
      (effects (font (size 1.27 1.27)) (justify left bottom) hide)
    )
    (property "Dielectric" "X5R" (at 191.77 8.89 0)
      (effects (font (size 1.27 1.27)) (justify left bottom) hide)
    )
    (property "Public" "False" (at 194.31 8.89 0)
      (effects (font (size 1.27 1.27)) (justify left bottom) hide)
    )
    (pin "1")
    (pin "2")
    (instances
      (project "ecp5-dc-scm"
        (path ""
          (reference "C254") (unit 1)
        )
      )
    )
  )

  (symbol (lib_id "antmicroCapacitors0402:C_100n_0402") (at 168.91 29.21 90) (unit 1)
    (in_bom yes) (on_board yes) (dnp no)
    (property "Reference" "C256" (at 162.56 24.13 90)
      (effects (font (size 1.524 1.524)) (justify right))
    )
    (property "Value" "C_100n_0402" (at 172.72 29.21 0)
      (effects (font (size 1.524 1.524)) hide)
    )
    (property "Footprint" "antmicro-footprints:C_0402_1005Metric" (at 163.83 24.13 0)
      (effects (font (size 1.524 1.524)) (justify left) hide)
    )
    (property "Datasheet" "https://www.murata.com/products/productdetail?partno=GRM155R61H104KE14%23" (at 168.91 29.21 0)
      (effects (font (size 1.27 1.27)) hide)
    )
    (property "Manufacturer" "Murata" (at 158.75 24.13 0)
      (effects (font (size 1.524 1.524)) (justify left) hide)
    )
    (property "MPN" "GRM155R61H104KE14D" (at 161.29 24.13 0)
      (effects (font (size 1.524 1.524)) (justify left) hide)
    )
    (property "Val" "100n" (at 163.83 29.21 90)
      (effects (font (size 1.27 1.27)) (justify right))
    )
    (property "License" "Apache-2.0" (at 191.77 8.89 0)
      (effects (font (size 1.27 1.27) (thickness 0.15)) (justify left bottom) hide)
    )
    (property "Author" "Antmicro" (at 194.31 8.89 0)
      (effects (font (size 1.27 1.27) (thickness 0.15)) (justify left bottom) hide)
    )
    (property "Voltage" "50V" (at 196.85 8.89 0)
      (effects (font (size 1.27 1.27)) (justify left bottom) hide)
    )
    (property "Dielectric" "X5R" (at 199.39 8.89 0)
      (effects (font (size 1.27 1.27)) (justify left bottom) hide)
    )
    (property "Public" "False" (at 201.93 8.89 0)
      (effects (font (size 1.27 1.27)) (justify left bottom) hide)
    )
    (pin "1")
    (pin "2")
    (instances
      (project "ecp5-dc-scm"
        (path ""
          (reference "C256") (unit 1)
        )
      )
    )
  )

  (symbol (lib_id "antmicroCapacitors0402:C_100n_0402") (at 176.53 29.21 90) (unit 1)
    (in_bom yes) (on_board yes) (dnp no)
    (property "Reference" "C258" (at 170.18 24.13 90)
      (effects (font (size 1.524 1.524)) (justify right))
    )
    (property "Value" "C_100n_0402" (at 180.34 29.21 0)
      (effects (font (size 1.524 1.524)) hide)
    )
    (property "Footprint" "antmicro-footprints:C_0402_1005Metric" (at 171.45 24.13 0)
      (effects (font (size 1.524 1.524)) (justify left) hide)
    )
    (property "Datasheet" "https://www.murata.com/products/productdetail?partno=GRM155R61H104KE14%23" (at 176.53 29.21 0)
      (effects (font (size 1.27 1.27)) hide)
    )
    (property "Manufacturer" "Murata" (at 166.37 24.13 0)
      (effects (font (size 1.524 1.524)) (justify left) hide)
    )
    (property "MPN" "GRM155R61H104KE14D" (at 168.91 24.13 0)
      (effects (font (size 1.524 1.524)) (justify left) hide)
    )
    (property "Val" "100n" (at 171.45 29.21 90)
      (effects (font (size 1.27 1.27)) (justify right))
    )
    (property "License" "Apache-2.0" (at 199.39 8.89 0)
      (effects (font (size 1.27 1.27) (thickness 0.15)) (justify left bottom) hide)
    )
    (property "Author" "Antmicro" (at 201.93 8.89 0)
      (effects (font (size 1.27 1.27) (thickness 0.15)) (justify left bottom) hide)
    )
    (property "Voltage" "50V" (at 204.47 8.89 0)
      (effects (font (size 1.27 1.27)) (justify left bottom) hide)
    )
    (property "Dielectric" "X5R" (at 207.01 8.89 0)
      (effects (font (size 1.27 1.27)) (justify left bottom) hide)
    )
    (property "Public" "False" (at 209.55 8.89 0)
      (effects (font (size 1.27 1.27)) (justify left bottom) hide)
    )
    (pin "1")
    (pin "2")
    (instances
      (project "ecp5-dc-scm"
        (path ""
          (reference "C258") (unit 1)
        )
      )
    )
  )

  (symbol (lib_id "antmicropower:GND") (at 153.67 31.75 0) (unit 1)
    (in_bom yes) (on_board yes) (dnp no)
    (property "Reference" "#PWR0133" (at 153.67 38.1 0)
      (effects (font (size 1.27 1.27)) hide)
    )
    (property "Value" "GND" (at 153.67 35.56 0)
      (effects (font (size 1.27 1.27)))
    )
    (property "Footprint" "" (at 153.67 31.75 0)
      (effects (font (size 1.27 1.27)) hide)
    )
    (property "Datasheet" "" (at 153.67 31.75 0)
      (effects (font (size 1.27 1.27)) hide)
    )
    (property "Author" "Antmicro" (at 162.56 39.37 0)
      (effects (font (size 1.27 1.27) (thickness 0.15)) (justify left bottom) hide)
    )
    (property "License" "Apache-2.0" (at 162.56 41.91 0)
      (effects (font (size 1.27 1.27) (thickness 0.15)) (justify left bottom) hide)
    )
    (pin "1")
    (instances
      (project "ecp5-dc-scm"
        (path ""
          (reference "#PWR0133") (unit 1)
        )
      )
    )
  )

  (symbol (lib_id "antmicropower:GND") (at 355.6 240.03 0) (unit 1)
    (in_bom yes) (on_board yes) (dnp no)
    (property "Reference" "#PWR0156" (at 355.6 246.38 0)
      (effects (font (size 1.27 1.27)) hide)
    )
    (property "Value" "GND" (at 355.727 244.4242 0)
      (effects (font (size 1.27 1.27)))
    )
    (property "Footprint" "" (at 355.6 240.03 0)
      (effects (font (size 1.27 1.27)) hide)
    )
    (property "Datasheet" "" (at 355.6 240.03 0)
      (effects (font (size 1.27 1.27)) hide)
    )
    (property "Author" "Antmicro" (at 364.49 247.65 0)
      (effects (font (size 1.27 1.27) (thickness 0.15)) (justify left bottom) hide)
    )
    (property "License" "Apache-2.0" (at 364.49 250.19 0)
      (effects (font (size 1.27 1.27) (thickness 0.15)) (justify left bottom) hide)
    )
    (pin "1")
    (instances
      (project "ecp5-dc-scm"
        (path ""
          (reference "#PWR0156") (unit 1)
        )
      )
    )
  )

  (symbol (lib_id "antmicropower:GND") (at 161.29 31.75 0) (unit 1)
    (in_bom yes) (on_board yes) (dnp no)
    (property "Reference" "#PWR0134" (at 161.29 38.1 0)
      (effects (font (size 1.27 1.27)) hide)
    )
    (property "Value" "GND" (at 161.29 35.56 0)
      (effects (font (size 1.27 1.27)))
    )
    (property "Footprint" "" (at 161.29 31.75 0)
      (effects (font (size 1.27 1.27)) hide)
    )
    (property "Datasheet" "" (at 161.29 31.75 0)
      (effects (font (size 1.27 1.27)) hide)
    )
    (property "Author" "Antmicro" (at 170.18 39.37 0)
      (effects (font (size 1.27 1.27) (thickness 0.15)) (justify left bottom) hide)
    )
    (property "License" "Apache-2.0" (at 170.18 41.91 0)
      (effects (font (size 1.27 1.27) (thickness 0.15)) (justify left bottom) hide)
    )
    (pin "1")
    (instances
      (project "ecp5-dc-scm"
        (path ""
          (reference "#PWR0134") (unit 1)
        )
      )
    )
  )

  (symbol (lib_id "antmicroResistors0402:R_1k_0402") (at 172.72 68.58 270) (unit 1)
    (in_bom yes) (on_board yes) (dnp no) (fields_autoplaced)
    (property "Reference" "R148" (at 175.26 69.85 90)
      (effects (font (size 1.524 1.524)) (justify left))
    )
    (property "Value" "R_1k_0402" (at 168.91 68.58 0)
      (effects (font (size 1.524 1.524)) hide)
    )
    (property "Footprint" "antmicro-footprints:R_0402_1005Metric" (at 177.8 73.66 0)
      (effects (font (size 1.524 1.524)) (justify left) hide)
    )
    (property "Datasheet" "https://www.bourns.com/docs/product-datasheets/cr.pdf" (at 172.72 68.58 0)
      (effects (font (size 1.27 1.27)) hide)
    )
    (property "Manufacturer" "Bourns" (at 182.88 73.66 0)
      (effects (font (size 1.524 1.524)) (justify left) hide)
    )
    (property "MPN" "CR0402-FX-1001GLF" (at 180.34 73.66 0)
      (effects (font (size 1.524 1.524)) (justify left) hide)
    )
    (property "Val" "1k" (at 175.26 72.39 90)
      (effects (font (size 1.27 1.27)) (justify left))
    )
    (property "License" "Apache-2.0" (at 147.32 88.9 0)
      (effects (font (size 1.27 1.27) (thickness 0.15)) (justify left bottom) hide)
    )
    (property "Author" "Antmicro" (at 144.78 88.9 0)
      (effects (font (size 1.27 1.27) (thickness 0.15)) (justify left bottom) hide)
    )
    (property "Tolerance" "1%" (at 162.56 88.9 0)
      (effects (font (size 1.27 1.27)) (justify left bottom) hide)
    )
    (property "Public" "False" (at 142.24 88.9 0)
      (effects (font (size 1.27 1.27)) (justify left bottom) hide)
    )
    (pin "1")
    (pin "2")
    (instances
      (project "ecp5-dc-scm"
        (path ""
          (reference "R148") (unit 1)
        )
      )
    )
  )

  (symbol (lib_id "antmicropower:GND") (at 168.91 31.75 0) (unit 1)
    (in_bom yes) (on_board yes) (dnp no)
    (property "Reference" "#PWR0135" (at 168.91 38.1 0)
      (effects (font (size 1.27 1.27)) hide)
    )
    (property "Value" "GND" (at 168.91 35.56 0)
      (effects (font (size 1.27 1.27)))
    )
    (property "Footprint" "" (at 168.91 31.75 0)
      (effects (font (size 1.27 1.27)) hide)
    )
    (property "Datasheet" "" (at 168.91 31.75 0)
      (effects (font (size 1.27 1.27)) hide)
    )
    (property "Author" "Antmicro" (at 177.8 39.37 0)
      (effects (font (size 1.27 1.27) (thickness 0.15)) (justify left bottom) hide)
    )
    (property "License" "Apache-2.0" (at 177.8 41.91 0)
      (effects (font (size 1.27 1.27) (thickness 0.15)) (justify left bottom) hide)
    )
    (pin "1")
    (instances
      (project "ecp5-dc-scm"
        (path ""
          (reference "#PWR0135") (unit 1)
        )
      )
    )
  )

  (symbol (lib_id "antmicropower:GND") (at 176.53 31.75 0) (unit 1)
    (in_bom yes) (on_board yes) (dnp no)
    (property "Reference" "#PWR0136" (at 176.53 38.1 0)
      (effects (font (size 1.27 1.27)) hide)
    )
    (property "Value" "GND" (at 176.53 35.56 0)
      (effects (font (size 1.27 1.27)))
    )
    (property "Footprint" "" (at 176.53 31.75 0)
      (effects (font (size 1.27 1.27)) hide)
    )
    (property "Datasheet" "" (at 176.53 31.75 0)
      (effects (font (size 1.27 1.27)) hide)
    )
    (property "Author" "Antmicro" (at 185.42 39.37 0)
      (effects (font (size 1.27 1.27) (thickness 0.15)) (justify left bottom) hide)
    )
    (property "License" "Apache-2.0" (at 185.42 41.91 0)
      (effects (font (size 1.27 1.27) (thickness 0.15)) (justify left bottom) hide)
    )
    (pin "1")
    (instances
      (project "ecp5-dc-scm"
        (path ""
          (reference "#PWR0136") (unit 1)
        )
      )
    )
  )

  (symbol (lib_id "antmicropower:GND") (at 45.72 53.34 0) (unit 1)
    (in_bom yes) (on_board yes) (dnp no)
    (property "Reference" "#PWR0150" (at 45.72 59.69 0)
      (effects (font (size 1.27 1.27)) hide)
    )
    (property "Value" "GND" (at 45.847 57.7342 0)
      (effects (font (size 1.27 1.27)))
    )
    (property "Footprint" "" (at 45.72 53.34 0)
      (effects (font (size 1.27 1.27)) hide)
    )
    (property "Datasheet" "" (at 45.72 53.34 0)
      (effects (font (size 1.27 1.27)) hide)
    )
    (property "Author" "Antmicro" (at 54.61 60.96 0)
      (effects (font (size 1.27 1.27) (thickness 0.15)) (justify left bottom) hide)
    )
    (property "License" "Apache-2.0" (at 54.61 63.5 0)
      (effects (font (size 1.27 1.27) (thickness 0.15)) (justify left bottom) hide)
    )
    (pin "1")
    (instances
      (project "ecp5-dc-scm"
        (path ""
          (reference "#PWR0150") (unit 1)
        )
      )
    )
  )

  (symbol (lib_id "antmicroCapacitors0402:C_100n_0402") (at 123.19 34.29 90) (unit 1)
    (in_bom yes) (on_board yes) (dnp no)
    (property "Reference" "C255" (at 116.84 29.21 90)
      (effects (font (size 1.524 1.524)) (justify right))
    )
    (property "Value" "C_100n_0402" (at 127 34.29 0)
      (effects (font (size 1.524 1.524)) hide)
    )
    (property "Footprint" "antmicro-footprints:C_0402_1005Metric" (at 118.11 29.21 0)
      (effects (font (size 1.524 1.524)) (justify left) hide)
    )
    (property "Datasheet" "https://www.murata.com/products/productdetail?partno=GRM155R61H104KE14%23" (at 123.19 34.29 0)
      (effects (font (size 1.27 1.27)) hide)
    )
    (property "Manufacturer" "Murata" (at 113.03 29.21 0)
      (effects (font (size 1.524 1.524)) (justify left) hide)
    )
    (property "MPN" "GRM155R61H104KE14D" (at 115.57 29.21 0)
      (effects (font (size 1.524 1.524)) (justify left) hide)
    )
    (property "Val" "100n" (at 118.11 34.29 90)
      (effects (font (size 1.27 1.27)) (justify right))
    )
    (property "License" "Apache-2.0" (at 146.05 13.97 0)
      (effects (font (size 1.27 1.27) (thickness 0.15)) (justify left bottom) hide)
    )
    (property "Author" "Antmicro" (at 148.59 13.97 0)
      (effects (font (size 1.27 1.27) (thickness 0.15)) (justify left bottom) hide)
    )
    (property "Voltage" "50V" (at 151.13 13.97 0)
      (effects (font (size 1.27 1.27)) (justify left bottom) hide)
    )
    (property "Dielectric" "X5R" (at 153.67 13.97 0)
      (effects (font (size 1.27 1.27)) (justify left bottom) hide)
    )
    (property "Public" "False" (at 156.21 13.97 0)
      (effects (font (size 1.27 1.27)) (justify left bottom) hide)
    )
    (pin "1")
    (pin "2")
    (instances
      (project "ecp5-dc-scm"
        (path ""
          (reference "C255") (unit 1)
        )
      )
    )
  )

  (symbol (lib_id "antmicroResistors0402:R_22R_0402") (at 123.19 240.03 0) (unit 1)
    (in_bom yes) (on_board yes) (dnp no) (fields_autoplaced)
    (property "Reference" "R14" (at 125.73 233.68 0)
      (effects (font (size 1.524 1.524)))
    )
    (property "Value" "R_22R_0402" (at 123.19 243.84 0)
      (effects (font (size 1.524 1.524)) hide)
    )
    (property "Footprint" "antmicro-footprints:R_0402_1005Metric" (at 128.27 234.95 0)
      (effects (font (size 1.524 1.524)) (justify left) hide)
    )
    (property "Datasheet" "https://www.bourns.com/docs/product-datasheets/cr.pdf" (at 123.19 240.03 0)
      (effects (font (size 1.27 1.27)) hide)
    )
    (property "Manufacturer" "Bourns" (at 128.27 229.87 0)
      (effects (font (size 1.524 1.524)) (justify left) hide)
    )
    (property "MPN" "CR0402-FX-22R0GLF" (at 128.27 232.41 0)
      (effects (font (size 1.524 1.524)) (justify left) hide)
    )
    (property "Val" "22R" (at 125.73 236.22 0)
      (effects (font (size 1.27 1.27)))
    )
    (property "License" "Apache-2.0" (at 143.51 265.43 0)
      (effects (font (size 1.27 1.27) (thickness 0.15)) (justify left bottom) hide)
    )
    (property "Author" "Antmicro" (at 143.51 267.97 0)
      (effects (font (size 1.27 1.27) (thickness 0.15)) (justify left bottom) hide)
    )
    (property "Tolerance" "1%" (at 143.51 250.19 0)
      (effects (font (size 1.27 1.27)) (justify left bottom) hide)
    )
    (property "Public" "False" (at 143.51 270.51 0)
      (effects (font (size 1.27 1.27)) (justify left bottom) hide)
    )
    (pin "1")
    (pin "2")
    (instances
      (project "ecp5-dc-scm"
        (path ""
          (reference "R14") (unit 1)
        )
      )
    )
  )

  (symbol (lib_id "antmicroCapacitors0402:C_10n_0402") (at 279.4 83.82 90) (unit 1)
    (in_bom yes) (on_board yes) (dnp no) (fields_autoplaced)
    (property "Reference" "C26" (at 276.86 80.0036 90)
      (effects (font (size 1.524 1.524)) (justify left))
    )
    (property "Value" "C_10n_0402" (at 283.21 83.82 0)
      (effects (font (size 1.524 1.524)) hide)
    )
    (property "Footprint" "antmicro-footprints:C_0402_1005Metric" (at 274.32 78.74 0)
      (effects (font (size 1.524 1.524)) (justify left) hide)
    )
    (property "Datasheet" "https://www.murata.com/products/productdetail?partno=GRM155R71H103KA88%23" (at 279.4 83.82 0)
      (effects (font (size 1.27 1.27)) hide)
    )
    (property "Manufacturer" "Murata" (at 269.24 78.74 0)
      (effects (font (size 1.524 1.524)) (justify left) hide)
    )
    (property "MPN" "GRM155R71H103KA88D" (at 271.78 78.74 0)
      (effects (font (size 1.524 1.524)) (justify left) hide)
    )
    (property "Val" "10n" (at 276.86 82.5436 90)
      (effects (font (size 1.27 1.27)) (justify left))
    )
    (property "License" "Apache-2.0" (at 302.26 63.5 0)
      (effects (font (size 1.27 1.27) (thickness 0.15)) (justify left bottom) hide)
    )
    (property "Author" "Antmicro" (at 304.8 63.5 0)
      (effects (font (size 1.27 1.27) (thickness 0.15)) (justify left bottom) hide)
    )
    (property "Voltage" "50V" (at 307.34 63.5 0)
      (effects (font (size 1.27 1.27)) (justify left bottom) hide)
    )
    (property "Dielectric" "X7R" (at 309.88 63.5 0)
      (effects (font (size 1.27 1.27)) (justify left bottom) hide)
    )
    (property "Public" "False" (at 312.42 63.5 0)
      (effects (font (size 1.27 1.27)) (justify left bottom) hide)
    )
    (pin "1")
    (pin "2")
    (instances
      (project "ecp5-dc-scm"
        (path ""
          (reference "C26") (unit 1)
        )
      )
    )
  )

  (symbol (lib_id "antmicropower:GND") (at 279.4 85.09 0) (unit 1)
    (in_bom yes) (on_board yes) (dnp no)
    (property "Reference" "#PWR041" (at 279.4 91.44 0)
      (effects (font (size 1.27 1.27)) hide)
    )
    (property "Value" "GND" (at 279.527 89.4842 0)
      (effects (font (size 1.27 1.27)))
    )
    (property "Footprint" "" (at 279.4 85.09 0)
      (effects (font (size 1.27 1.27)) hide)
    )
    (property "Datasheet" "" (at 279.4 85.09 0)
      (effects (font (size 1.27 1.27)) hide)
    )
    (property "Author" "Antmicro" (at 288.29 92.71 0)
      (effects (font (size 1.27 1.27) (thickness 0.15)) (justify left bottom) hide)
    )
    (property "License" "Apache-2.0" (at 288.29 95.25 0)
      (effects (font (size 1.27 1.27) (thickness 0.15)) (justify left bottom) hide)
    )
    (pin "1")
    (instances
      (project "ecp5-dc-scm"
        (path ""
          (reference "#PWR041") (unit 1)
        )
      )
    )
  )

  (symbol (lib_id "antmicropower:GND") (at 295.91 87.63 0) (unit 1)
    (in_bom yes) (on_board yes) (dnp no)
    (property "Reference" "#PWR033" (at 295.91 93.98 0)
      (effects (font (size 1.27 1.27)) hide)
    )
    (property "Value" "GND" (at 296.037 92.0242 0)
      (effects (font (size 1.27 1.27)))
    )
    (property "Footprint" "" (at 295.91 87.63 0)
      (effects (font (size 1.27 1.27)) hide)
    )
    (property "Datasheet" "" (at 295.91 87.63 0)
      (effects (font (size 1.27 1.27)) hide)
    )
    (property "Author" "Antmicro" (at 304.8 95.25 0)
      (effects (font (size 1.27 1.27) (thickness 0.15)) (justify left bottom) hide)
    )
    (property "License" "Apache-2.0" (at 304.8 97.79 0)
      (effects (font (size 1.27 1.27) (thickness 0.15)) (justify left bottom) hide)
    )
    (pin "1")
    (instances
      (project "ecp5-dc-scm"
        (path ""
          (reference "#PWR033") (unit 1)
        )
      )
    )
  )

  (symbol (lib_id "antmicropower:GND") (at 123.19 36.83 0) (unit 1)
    (in_bom yes) (on_board yes) (dnp no)
    (property "Reference" "#PWR0137" (at 123.19 43.18 0)
      (effects (font (size 1.27 1.27)) hide)
    )
    (property "Value" "GND" (at 123.317 41.2242 0)
      (effects (font (size 1.27 1.27)))
    )
    (property "Footprint" "" (at 123.19 36.83 0)
      (effects (font (size 1.27 1.27)) hide)
    )
    (property "Datasheet" "" (at 123.19 36.83 0)
      (effects (font (size 1.27 1.27)) hide)
    )
    (property "Author" "Antmicro" (at 132.08 44.45 0)
      (effects (font (size 1.27 1.27) (thickness 0.15)) (justify left bottom) hide)
    )
    (property "License" "Apache-2.0" (at 132.08 46.99 0)
      (effects (font (size 1.27 1.27) (thickness 0.15)) (justify left bottom) hide)
    )
    (pin "1")
    (instances
      (project "ecp5-dc-scm"
        (path ""
          (reference "#PWR0137") (unit 1)
        )
      )
    )
  )

  (symbol (lib_id "antmicropower:GND") (at 132.08 36.83 0) (unit 1)
    (in_bom yes) (on_board yes) (dnp no)
    (property "Reference" "#PWR0138" (at 132.08 43.18 0)
      (effects (font (size 1.27 1.27)) hide)
    )
    (property "Value" "GND" (at 132.207 41.2242 0)
      (effects (font (size 1.27 1.27)))
    )
    (property "Footprint" "" (at 132.08 36.83 0)
      (effects (font (size 1.27 1.27)) hide)
    )
    (property "Datasheet" "" (at 132.08 36.83 0)
      (effects (font (size 1.27 1.27)) hide)
    )
    (property "Author" "Antmicro" (at 140.97 44.45 0)
      (effects (font (size 1.27 1.27) (thickness 0.15)) (justify left bottom) hide)
    )
    (property "License" "Apache-2.0" (at 140.97 46.99 0)
      (effects (font (size 1.27 1.27) (thickness 0.15)) (justify left bottom) hide)
    )
    (pin "1")
    (instances
      (project "ecp5-dc-scm"
        (path ""
          (reference "#PWR0138") (unit 1)
        )
      )
    )
  )

  (symbol (lib_id "antmicroCapacitors0402:C_100n_0402") (at 137.16 53.34 270) (mirror x) (unit 1)
    (in_bom yes) (on_board yes) (dnp no)
    (property "Reference" "C249" (at 134.62 49.5236 90)
      (effects (font (size 1.524 1.524)) (justify right))
    )
    (property "Value" "C_100n_0402" (at 133.35 53.34 0)
      (effects (font (size 1.524 1.524)) hide)
    )
    (property "Footprint" "antmicro-footprints:C_0402_1005Metric" (at 142.24 48.26 0)
      (effects (font (size 1.524 1.524)) (justify left) hide)
    )
    (property "Datasheet" "https://www.murata.com/products/productdetail?partno=GRM155R61H104KE14%23" (at 137.16 53.34 0)
      (effects (font (size 1.27 1.27)) hide)
    )
    (property "Manufacturer" "Murata" (at 147.32 48.26 0)
      (effects (font (size 1.524 1.524)) (justify left) hide)
    )
    (property "MPN" "GRM155R61H104KE14D" (at 144.78 48.26 0)
      (effects (font (size 1.524 1.524)) (justify left) hide)
    )
    (property "Val" "100n" (at 134.62 52.0636 90)
      (effects (font (size 1.27 1.27)) (justify right))
    )
    (property "License" "Apache-2.0" (at 114.3 33.02 0)
      (effects (font (size 1.27 1.27) (thickness 0.15)) (justify left bottom) hide)
    )
    (property "Author" "Antmicro" (at 111.76 33.02 0)
      (effects (font (size 1.27 1.27) (thickness 0.15)) (justify left bottom) hide)
    )
    (property "Voltage" "50V" (at 109.22 33.02 0)
      (effects (font (size 1.27 1.27)) (justify left bottom) hide)
    )
    (property "Dielectric" "X5R" (at 106.68 33.02 0)
      (effects (font (size 1.27 1.27)) (justify left bottom) hide)
    )
    (property "Public" "False" (at 104.14 33.02 0)
      (effects (font (size 1.27 1.27)) (justify left bottom) hide)
    )
    (pin "1")
    (pin "2")
    (instances
      (project "ecp5-dc-scm"
        (path ""
          (reference "C249") (unit 1)
        )
      )
    )
  )

  (symbol (lib_id "antmicroCapacitors0402:C_4u7_0402") (at 144.78 53.34 90) (unit 1)
    (in_bom yes) (on_board yes) (dnp no)
    (property "Reference" "C252" (at 138.43 49.53 90)
      (effects (font (size 1.524 1.524)) (justify right))
    )
    (property "Value" "C_4u7_0402" (at 148.59 53.34 0)
      (effects (font (size 1.524 1.524)) hide)
    )
    (property "Footprint" "antmicro-footprints:C_0402_1005Metric" (at 139.7 48.26 0)
      (effects (font (size 1.524 1.524)) (justify left) hide)
    )
    (property "Datasheet" "https://www.murata.com/products/productdetail?partno=GRM155R61A475MEAA%23" (at 144.78 53.34 0)
      (effects (font (size 1.27 1.27)) hide)
    )
    (property "Manufacturer" "Murata" (at 134.62 48.26 0)
      (effects (font (size 1.524 1.524)) (justify left) hide)
    )
    (property "MPN" "GRM155R61A475MEAAD" (at 137.16 48.26 0)
      (effects (font (size 1.524 1.524)) (justify left) hide)
    )
    (property "Val" "4u7" (at 138.43 52.07 90)
      (effects (font (size 1.27 1.27)) (justify right))
    )
    (property "License" "Apache-2.0" (at 167.64 33.02 0)
      (effects (font (size 1.27 1.27) (thickness 0.15)) (justify left bottom) hide)
    )
    (property "Author" "Antmicro" (at 170.18 33.02 0)
      (effects (font (size 1.27 1.27) (thickness 0.15)) (justify left bottom) hide)
    )
    (property "Voltage" "" (at 172.72 33.02 0)
      (effects (font (size 1.27 1.27)) (justify left bottom) hide)
    )
    (property "Dielectric" "" (at 175.26 33.02 0)
      (effects (font (size 1.27 1.27)) (justify left bottom) hide)
    )
    (property "Public" "False" (at 177.8 33.02 0)
      (effects (font (size 1.27 1.27)) (justify left bottom) hide)
    )
    (pin "1")
    (pin "2")
    (instances
      (project "ecp5-dc-scm"
        (path ""
          (reference "C252") (unit 1)
        )
      )
    )
  )

  (symbol (lib_id "antmicropower:GND") (at 137.16 54.61 0) (unit 1)
    (in_bom yes) (on_board yes) (dnp no)
    (property "Reference" "#PWR0139" (at 137.16 60.96 0)
      (effects (font (size 1.27 1.27)) hide)
    )
    (property "Value" "GND" (at 137.287 59.0042 0)
      (effects (font (size 1.27 1.27)))
    )
    (property "Footprint" "" (at 137.16 54.61 0)
      (effects (font (size 1.27 1.27)) hide)
    )
    (property "Datasheet" "" (at 137.16 54.61 0)
      (effects (font (size 1.27 1.27)) hide)
    )
    (property "Author" "Antmicro" (at 146.05 62.23 0)
      (effects (font (size 1.27 1.27) (thickness 0.15)) (justify left bottom) hide)
    )
    (property "License" "Apache-2.0" (at 146.05 64.77 0)
      (effects (font (size 1.27 1.27) (thickness 0.15)) (justify left bottom) hide)
    )
    (pin "1")
    (instances
      (project "ecp5-dc-scm"
        (path ""
          (reference "#PWR0139") (unit 1)
        )
      )
    )
  )

  (symbol (lib_id "antmicropower:GND") (at 144.78 54.61 0) (unit 1)
    (in_bom yes) (on_board yes) (dnp no)
    (property "Reference" "#PWR0140" (at 144.78 60.96 0)
      (effects (font (size 1.27 1.27)) hide)
    )
    (property "Value" "GND" (at 144.907 59.0042 0)
      (effects (font (size 1.27 1.27)))
    )
    (property "Footprint" "" (at 144.78 54.61 0)
      (effects (font (size 1.27 1.27)) hide)
    )
    (property "Datasheet" "" (at 144.78 54.61 0)
      (effects (font (size 1.27 1.27)) hide)
    )
    (property "Author" "Antmicro" (at 153.67 62.23 0)
      (effects (font (size 1.27 1.27) (thickness 0.15)) (justify left bottom) hide)
    )
    (property "License" "Apache-2.0" (at 153.67 64.77 0)
      (effects (font (size 1.27 1.27) (thickness 0.15)) (justify left bottom) hide)
    )
    (pin "1")
    (instances
      (project "ecp5-dc-scm"
        (path ""
          (reference "#PWR0140") (unit 1)
        )
      )
    )
  )

  (symbol (lib_id "antmicroCapacitors0402:C_100n_0402") (at 135.89 67.31 90) (unit 1)
    (in_bom yes) (on_board yes) (dnp no)
    (property "Reference" "C227" (at 134.62 63.5 90)
      (effects (font (size 1.524 1.524)) (justify left))
    )
    (property "Value" "C_100n_0402" (at 139.7 67.31 0)
      (effects (font (size 1.524 1.524)) hide)
    )
    (property "Footprint" "antmicro-footprints:C_0402_1005Metric" (at 130.81 62.23 0)
      (effects (font (size 1.524 1.524)) (justify left) hide)
    )
    (property "Datasheet" "https://www.murata.com/products/productdetail?partno=GRM155R61H104KE14%23" (at 135.89 67.31 0)
      (effects (font (size 1.27 1.27)) hide)
    )
    (property "Manufacturer" "Murata" (at 125.73 62.23 0)
      (effects (font (size 1.524 1.524)) (justify left) hide)
    )
    (property "MPN" "GRM155R61H104KE14D" (at 128.27 62.23 0)
      (effects (font (size 1.524 1.524)) (justify left) hide)
    )
    (property "Val" "100n" (at 134.62 66.04 90)
      (effects (font (size 1.27 1.27)) (justify left))
    )
    (property "License" "Apache-2.0" (at 158.75 46.99 0)
      (effects (font (size 1.27 1.27) (thickness 0.15)) (justify left bottom) hide)
    )
    (property "Author" "Antmicro" (at 161.29 46.99 0)
      (effects (font (size 1.27 1.27) (thickness 0.15)) (justify left bottom) hide)
    )
    (property "Voltage" "50V" (at 163.83 46.99 0)
      (effects (font (size 1.27 1.27)) (justify left bottom) hide)
    )
    (property "Dielectric" "X5R" (at 166.37 46.99 0)
      (effects (font (size 1.27 1.27)) (justify left bottom) hide)
    )
    (property "Public" "False" (at 168.91 46.99 0)
      (effects (font (size 1.27 1.27)) (justify left bottom) hide)
    )
    (pin "1")
    (pin "2")
    (instances
      (project "ecp5-dc-scm"
        (path ""
          (reference "C227") (unit 1)
        )
      )
    )
  )

  (symbol (lib_id "antmicroCapacitors0402:C_4u7_0402") (at 143.51 67.31 90) (unit 1)
    (in_bom yes) (on_board yes) (dnp no)
    (property "Reference" "C250" (at 144.78 63.5 90)
      (effects (font (size 1.524 1.524)) (justify right))
    )
    (property "Value" "C_4u7_0402" (at 147.32 67.31 0)
      (effects (font (size 1.524 1.524)) hide)
    )
    (property "Footprint" "antmicro-footprints:C_0402_1005Metric" (at 138.43 62.23 0)
      (effects (font (size 1.524 1.524)) (justify left) hide)
    )
    (property "Datasheet" "https://www.murata.com/products/productdetail?partno=GRM155R61A475MEAA%23" (at 143.51 67.31 0)
      (effects (font (size 1.27 1.27)) hide)
    )
    (property "Manufacturer" "Murata" (at 133.35 62.23 0)
      (effects (font (size 1.524 1.524)) (justify left) hide)
    )
    (property "MPN" "GRM155R61A475MEAAD" (at 135.89 62.23 0)
      (effects (font (size 1.524 1.524)) (justify left) hide)
    )
    (property "Val" "4u7" (at 144.78 66.04 90)
      (effects (font (size 1.27 1.27)) (justify right))
    )
    (property "License" "Apache-2.0" (at 166.37 46.99 0)
      (effects (font (size 1.27 1.27) (thickness 0.15)) (justify left bottom) hide)
    )
    (property "Author" "Antmicro" (at 168.91 46.99 0)
      (effects (font (size 1.27 1.27) (thickness 0.15)) (justify left bottom) hide)
    )
    (property "Voltage" "" (at 171.45 46.99 0)
      (effects (font (size 1.27 1.27)) (justify left bottom) hide)
    )
    (property "Dielectric" "" (at 173.99 46.99 0)
      (effects (font (size 1.27 1.27)) (justify left bottom) hide)
    )
    (property "Public" "False" (at 176.53 46.99 0)
      (effects (font (size 1.27 1.27)) (justify left bottom) hide)
    )
    (pin "1")
    (pin "2")
    (instances
      (project "ecp5-dc-scm"
        (path ""
          (reference "C250") (unit 1)
        )
      )
    )
  )

  (symbol (lib_id "antmicropower:GND") (at 135.89 68.58 0) (unit 1)
    (in_bom yes) (on_board yes) (dnp no)
    (property "Reference" "#PWR0141" (at 135.89 74.93 0)
      (effects (font (size 1.27 1.27)) hide)
    )
    (property "Value" "GND" (at 136.017 72.9742 0)
      (effects (font (size 1.27 1.27)))
    )
    (property "Footprint" "" (at 135.89 68.58 0)
      (effects (font (size 1.27 1.27)) hide)
    )
    (property "Datasheet" "" (at 135.89 68.58 0)
      (effects (font (size 1.27 1.27)) hide)
    )
    (property "Author" "Antmicro" (at 144.78 76.2 0)
      (effects (font (size 1.27 1.27) (thickness 0.15)) (justify left bottom) hide)
    )
    (property "License" "Apache-2.0" (at 144.78 78.74 0)
      (effects (font (size 1.27 1.27) (thickness 0.15)) (justify left bottom) hide)
    )
    (pin "1")
    (instances
      (project "ecp5-dc-scm"
        (path ""
          (reference "#PWR0141") (unit 1)
        )
      )
    )
  )

  (symbol (lib_id "antmicropower:GND") (at 143.51 68.58 0) (unit 1)
    (in_bom yes) (on_board yes) (dnp no)
    (property "Reference" "#PWR0142" (at 143.51 74.93 0)
      (effects (font (size 1.27 1.27)) hide)
    )
    (property "Value" "GND" (at 143.637 72.9742 0)
      (effects (font (size 1.27 1.27)))
    )
    (property "Footprint" "" (at 143.51 68.58 0)
      (effects (font (size 1.27 1.27)) hide)
    )
    (property "Datasheet" "" (at 143.51 68.58 0)
      (effects (font (size 1.27 1.27)) hide)
    )
    (property "Author" "Antmicro" (at 152.4 76.2 0)
      (effects (font (size 1.27 1.27) (thickness 0.15)) (justify left bottom) hide)
    )
    (property "License" "Apache-2.0" (at 152.4 78.74 0)
      (effects (font (size 1.27 1.27) (thickness 0.15)) (justify left bottom) hide)
    )
    (pin "1")
    (instances
      (project "ecp5-dc-scm"
        (path ""
          (reference "#PWR0142") (unit 1)
        )
      )
    )
  )

  (symbol (lib_id "antmicroCapacitors0402:C_4u7_0402") (at 74.93 251.46 90) (unit 1)
    (in_bom yes) (on_board yes) (dnp no) (fields_autoplaced)
    (property "Reference" "C53" (at 72.39 247.6436 90)
      (effects (font (size 1.524 1.524)) (justify left))
    )
    (property "Value" "C_4u7_0402" (at 78.74 251.46 0)
      (effects (font (size 1.524 1.524)) hide)
    )
    (property "Footprint" "antmicro-footprints:C_0402_1005Metric" (at 69.85 246.38 0)
      (effects (font (size 1.524 1.524)) (justify left) hide)
    )
    (property "Datasheet" "https://www.murata.com/products/productdetail?partno=GRM155R61A475MEAA%23" (at 74.93 251.46 0)
      (effects (font (size 1.27 1.27)) hide)
    )
    (property "Manufacturer" "Murata" (at 64.77 246.38 0)
      (effects (font (size 1.524 1.524)) (justify left) hide)
    )
    (property "MPN" "GRM155R61A475MEAAD" (at 67.31 246.38 0)
      (effects (font (size 1.524 1.524)) (justify left) hide)
    )
    (property "Val" "4u7" (at 72.39 250.1836 90)
      (effects (font (size 1.27 1.27)) (justify left))
    )
    (property "License" "Apache-2.0" (at 97.79 231.14 0)
      (effects (font (size 1.27 1.27) (thickness 0.15)) (justify left bottom) hide)
    )
    (property "Author" "Antmicro" (at 100.33 231.14 0)
      (effects (font (size 1.27 1.27) (thickness 0.15)) (justify left bottom) hide)
    )
    (property "Voltage" "" (at 102.87 231.14 0)
      (effects (font (size 1.27 1.27)) (justify left bottom) hide)
    )
    (property "Dielectric" "" (at 105.41 231.14 0)
      (effects (font (size 1.27 1.27)) (justify left bottom) hide)
    )
    (property "Public" "False" (at 107.95 231.14 0)
      (effects (font (size 1.27 1.27)) (justify left bottom) hide)
    )
    (pin "1")
    (pin "2")
    (instances
      (project "ecp5-dc-scm"
        (path ""
          (reference "C53") (unit 1)
        )
      )
    )
  )

  (symbol (lib_id "antmicroCapacitors0402:C_100n_0402") (at 81.28 251.46 90) (unit 1)
    (in_bom yes) (on_board yes) (dnp no) (fields_autoplaced)
    (property "Reference" "C54" (at 83.82 247.6436 90)
      (effects (font (size 1.524 1.524)) (justify right))
    )
    (property "Value" "C_100n_0402" (at 85.09 251.46 0)
      (effects (font (size 1.524 1.524)) hide)
    )
    (property "Footprint" "antmicro-footprints:C_0402_1005Metric" (at 76.2 246.38 0)
      (effects (font (size 1.524 1.524)) (justify left) hide)
    )
    (property "Datasheet" "https://www.murata.com/products/productdetail?partno=GRM155R61H104KE14%23" (at 81.28 251.46 0)
      (effects (font (size 1.27 1.27)) hide)
    )
    (property "Manufacturer" "Murata" (at 71.12 246.38 0)
      (effects (font (size 1.524 1.524)) (justify left) hide)
    )
    (property "MPN" "GRM155R61H104KE14D" (at 73.66 246.38 0)
      (effects (font (size 1.524 1.524)) (justify left) hide)
    )
    (property "Val" "100n" (at 83.82 250.1836 90)
      (effects (font (size 1.27 1.27)) (justify right))
    )
    (property "License" "Apache-2.0" (at 104.14 231.14 0)
      (effects (font (size 1.27 1.27) (thickness 0.15)) (justify left bottom) hide)
    )
    (property "Author" "Antmicro" (at 106.68 231.14 0)
      (effects (font (size 1.27 1.27) (thickness 0.15)) (justify left bottom) hide)
    )
    (property "Voltage" "50V" (at 109.22 231.14 0)
      (effects (font (size 1.27 1.27)) (justify left bottom) hide)
    )
    (property "Dielectric" "X5R" (at 111.76 231.14 0)
      (effects (font (size 1.27 1.27)) (justify left bottom) hide)
    )
    (property "Public" "False" (at 114.3 231.14 0)
      (effects (font (size 1.27 1.27)) (justify left bottom) hide)
    )
    (pin "1")
    (pin "2")
    (instances
      (project "ecp5-dc-scm"
        (path ""
          (reference "C54") (unit 1)
        )
      )
    )
  )

  (symbol (lib_id "antmicropower:GND") (at 81.28 254 0) (mirror y) (unit 1)
    (in_bom yes) (on_board yes) (dnp no)
    (property "Reference" "#PWR032" (at 81.28 260.35 0)
      (effects (font (size 1.27 1.27)) hide)
    )
    (property "Value" "GND" (at 81.153 258.3942 0)
      (effects (font (size 1.27 1.27)))
    )
    (property "Footprint" "" (at 81.28 254 0)
      (effects (font (size 1.27 1.27)) hide)
    )
    (property "Datasheet" "" (at 81.28 254 0)
      (effects (font (size 1.27 1.27)) hide)
    )
    (property "Author" "Antmicro" (at 72.39 261.62 0)
      (effects (font (size 1.27 1.27) (thickness 0.15)) (justify left bottom) hide)
    )
    (property "License" "Apache-2.0" (at 72.39 264.16 0)
      (effects (font (size 1.27 1.27) (thickness 0.15)) (justify left bottom) hide)
    )
    (pin "1")
    (instances
      (project "ecp5-dc-scm"
        (path ""
          (reference "#PWR032") (unit 1)
        )
      )
    )
  )

  (symbol (lib_id "antmicroFerriteBeadsandChips:FB_600Z_0.3A_Murata-BLM15AG_0402") (at 121.92 46.99 0) (unit 1)
    (in_bom yes) (on_board yes) (dnp no)
    (property "Reference" "FB10" (at 118.11 45.72 0)
      (effects (font (size 1.524 1.524)))
    )
    (property "Value" "FB_600Z_0.3A_Murata-BLM15AG_0402" (at 118.11 43.18 0)
      (effects (font (size 1.524 1.524)) hide)
    )
    (property "Footprint" "antmicro-footprints:FB_0402_1005Metric" (at 127 41.91 0)
      (effects (font (size 1.524 1.524)) (justify left) hide)
    )
    (property "Datasheet" "https://www.murata.com/en-us/products/productdata/8796740059166/ENFA0018.pdf" (at 127 39.37 0)
      (effects (font (size 1.524 1.524)) (justify left) hide)
    )
    (property "MPN" "BLM15AG601SN1D" (at 127 34.29 0)
      (effects (font (size 1.524 1.524)) (justify left) hide)
    )
    (property "Manufacturer" "Murata" (at 127 19.05 0)
      (effects (font (size 1.524 1.524)) (justify left) hide)
    )
    (property "Val" "600Z/0.3A" (at 118.11 49.53 0)
      (effects (font (size 1.27 1.27)))
    )
    (property "Current" "" (at 142.24 69.85 0)
      (effects (font (size 1.27 1.27) (thickness 0.15)) (justify left bottom) hide)
    )
    (property "Author" "Antmicro" (at 137.16 64.77 0)
      (effects (font (size 1.27 1.27) (thickness 0.15)) (justify left bottom) hide)
    )
    (property "License" "Apache-2.0" (at 137.16 67.31 0)
      (effects (font (size 1.27 1.27) (thickness 0.15)) (justify left bottom) hide)
    )
    (property "Public" "False" (at 142.24 62.23 0)
      (effects (font (size 1.27 1.27)) (justify left bottom) hide)
    )
    (pin "1")
    (pin "2")
    (instances
      (project "ecp5-dc-scm"
        (path ""
          (reference "FB10") (unit 1)
        )
      )
    )
  )

  (symbol (lib_id "antmicroFerriteBeadsandChips:FB_600Z_0.3A_Murata-BLM15AG_0402") (at 121.92 60.96 0) (unit 1)
    (in_bom yes) (on_board yes) (dnp no)
    (property "Reference" "FB9" (at 118.11 59.69 0)
      (effects (font (size 1.524 1.524)))
    )
    (property "Value" "FB_600Z_0.3A_Murata-BLM15AG_0402" (at 116.84 66.0654 0)
      (effects (font (size 1.524 1.524)) hide)
    )
    (property "Footprint" "antmicro-footprints:FB_0402_1005Metric" (at 127 55.88 0)
      (effects (font (size 1.524 1.524)) (justify left) hide)
    )
    (property "Datasheet" "https://www.murata.com/en-us/products/productdata/8796740059166/ENFA0018.pdf" (at 127 53.34 0)
      (effects (font (size 1.524 1.524)) (justify left) hide)
    )
    (property "MPN" "BLM15AG601SN1D" (at 127 48.26 0)
      (effects (font (size 1.524 1.524)) (justify left) hide)
    )
    (property "Manufacturer" "Murata" (at 127 33.02 0)
      (effects (font (size 1.524 1.524)) (justify left) hide)
    )
    (property "Val" "600Z/0.3A" (at 113.03 64.77 0)
      (effects (font (size 1.27 1.27)) (justify left bottom))
    )
    (property "Current" "" (at 142.24 83.82 0)
      (effects (font (size 1.27 1.27) (thickness 0.15)) (justify left bottom) hide)
    )
    (property "Author" "Antmicro" (at 137.16 78.74 0)
      (effects (font (size 1.27 1.27) (thickness 0.15)) (justify left bottom) hide)
    )
    (property "License" "Apache-2.0" (at 137.16 81.28 0)
      (effects (font (size 1.27 1.27) (thickness 0.15)) (justify left bottom) hide)
    )
    (property "Public" "False" (at 142.24 76.2 0)
      (effects (font (size 1.27 1.27)) (justify left bottom) hide)
    )
    (pin "1")
    (pin "2")
    (instances
      (project "ecp5-dc-scm"
        (path ""
          (reference "FB9") (unit 1)
        )
      )
    )
  )

  (symbol (lib_id "antmicroCapacitors0603:C_22u_0603") (at 43.18 227.33 90) (unit 1)
    (in_bom yes) (on_board yes) (dnp no)
    (property "Reference" "C48" (at 40.64 224.79 0)
      (effects (font (size 1.524 1.524)) (justify left))
    )
    (property "Value" "C_22u_0603" (at 46.99 227.33 0)
      (effects (font (size 1.524 1.524)) hide)
    )
    (property "Footprint" "antmicro-footprints:C_0603_1608Metric" (at 38.1 222.25 0)
      (effects (font (size 1.524 1.524)) (justify left) hide)
    )
    (property "Datasheet" "https://www.murata.com/products/productdetail?partno=GRM188R60J226MEA0%23" (at 43.18 227.33 0)
      (effects (font (size 1.27 1.27)) hide)
    )
    (property "Manufacturer" "Murata" (at 33.02 222.25 0)
      (effects (font (size 1.524 1.524)) (justify left) hide)
    )
    (property "MPN" "GRM188R60J226MEA0D" (at 35.56 222.25 0)
      (effects (font (size 1.524 1.524)) (justify left) hide)
    )
    (property "Val" "22u" (at 40.64 228.6 0)
      (effects (font (size 1.27 1.27)) (justify left))
    )
    (property "License" "Apache-2.0" (at 66.04 207.01 0)
      (effects (font (size 1.27 1.27) (thickness 0.15)) (justify left bottom) hide)
    )
    (property "Author" "Antmicro" (at 68.58 207.01 0)
      (effects (font (size 1.27 1.27) (thickness 0.15)) (justify left bottom) hide)
    )
    (property "Voltage" "" (at 71.12 207.01 0)
      (effects (font (size 1.27 1.27)) (justify left bottom) hide)
    )
    (property "Dielectric" "" (at 73.66 207.01 0)
      (effects (font (size 1.27 1.27)) (justify left bottom) hide)
    )
    (property "Public" "False" (at 76.2 207.01 0)
      (effects (font (size 1.27 1.27)) (justify left bottom) hide)
    )
    (pin "1")
    (pin "2")
    (instances
      (project "ecp5-dc-scm"
        (path ""
          (reference "C48") (unit 1)
        )
      )
    )
  )

  (symbol (lib_id "antmicroCapacitors0603:C_22u_0603") (at 50.8 227.33 90) (unit 1)
    (in_bom yes) (on_board yes) (dnp no)
    (property "Reference" "C49" (at 48.26 219.71 0)
      (effects (font (size 1.524 1.524)) (justify right))
    )
    (property "Value" "C_22u_0603" (at 54.61 227.33 0)
      (effects (font (size 1.524 1.524)) hide)
    )
    (property "Footprint" "antmicro-footprints:C_0603_1608Metric" (at 45.72 222.25 0)
      (effects (font (size 1.524 1.524)) (justify left) hide)
    )
    (property "Datasheet" "https://www.murata.com/products/productdetail?partno=GRM188R60J226MEA0%23" (at 50.8 227.33 0)
      (effects (font (size 1.27 1.27)) hide)
    )
    (property "Manufacturer" "Murata" (at 40.64 222.25 0)
      (effects (font (size 1.524 1.524)) (justify left) hide)
    )
    (property "MPN" "GRM188R60J226MEA0D" (at 43.18 222.25 0)
      (effects (font (size 1.524 1.524)) (justify left) hide)
    )
    (property "Val" "22u" (at 48.26 224.79 0)
      (effects (font (size 1.27 1.27)) (justify right))
    )
    (property "License" "Apache-2.0" (at 73.66 207.01 0)
      (effects (font (size 1.27 1.27) (thickness 0.15)) (justify left bottom) hide)
    )
    (property "Author" "Antmicro" (at 76.2 207.01 0)
      (effects (font (size 1.27 1.27) (thickness 0.15)) (justify left bottom) hide)
    )
    (property "Voltage" "" (at 78.74 207.01 0)
      (effects (font (size 1.27 1.27)) (justify left bottom) hide)
    )
    (property "Dielectric" "" (at 81.28 207.01 0)
      (effects (font (size 1.27 1.27)) (justify left bottom) hide)
    )
    (property "Public" "False" (at 83.82 207.01 0)
      (effects (font (size 1.27 1.27)) (justify left bottom) hide)
    )
    (pin "1")
    (pin "2")
    (instances
      (project "ecp5-dc-scm"
        (path ""
          (reference "C49") (unit 1)
        )
      )
    )
  )

  (symbol (lib_id "antmicroCapacitors0603:C_22u_0603") (at 58.42 227.33 90) (unit 1)
    (in_bom yes) (on_board yes) (dnp no)
    (property "Reference" "C50" (at 55.88 219.71 0)
      (effects (font (size 1.524 1.524)) (justify right))
    )
    (property "Value" "C_22u_0603" (at 62.23 227.33 0)
      (effects (font (size 1.524 1.524)) hide)
    )
    (property "Footprint" "antmicro-footprints:C_0603_1608Metric" (at 53.34 222.25 0)
      (effects (font (size 1.524 1.524)) (justify left) hide)
    )
    (property "Datasheet" "https://www.murata.com/products/productdetail?partno=GRM188R60J226MEA0%23" (at 58.42 227.33 0)
      (effects (font (size 1.27 1.27)) hide)
    )
    (property "Manufacturer" "Murata" (at 48.26 222.25 0)
      (effects (font (size 1.524 1.524)) (justify left) hide)
    )
    (property "MPN" "GRM188R60J226MEA0D" (at 50.8 222.25 0)
      (effects (font (size 1.524 1.524)) (justify left) hide)
    )
    (property "Val" "22u" (at 55.88 224.79 0)
      (effects (font (size 1.27 1.27)) (justify right))
    )
    (property "License" "Apache-2.0" (at 81.28 207.01 0)
      (effects (font (size 1.27 1.27) (thickness 0.15)) (justify left bottom) hide)
    )
    (property "Author" "Antmicro" (at 83.82 207.01 0)
      (effects (font (size 1.27 1.27) (thickness 0.15)) (justify left bottom) hide)
    )
    (property "Voltage" "" (at 86.36 207.01 0)
      (effects (font (size 1.27 1.27)) (justify left bottom) hide)
    )
    (property "Dielectric" "" (at 88.9 207.01 0)
      (effects (font (size 1.27 1.27)) (justify left bottom) hide)
    )
    (property "Public" "False" (at 91.44 207.01 0)
      (effects (font (size 1.27 1.27)) (justify left bottom) hide)
    )
    (pin "1")
    (pin "2")
    (instances
      (project "ecp5-dc-scm"
        (path ""
          (reference "C50") (unit 1)
        )
      )
    )
  )

  (symbol (lib_id "antmicroCapacitors0402:C_100n_0402") (at 67.31 227.33 90) (unit 1)
    (in_bom yes) (on_board yes) (dnp no)
    (property "Reference" "C51" (at 64.77 219.71 0)
      (effects (font (size 1.524 1.524)) (justify right))
    )
    (property "Value" "C_100n_0402" (at 71.12 227.33 0)
      (effects (font (size 1.524 1.524)) hide)
    )
    (property "Footprint" "antmicro-footprints:C_0402_1005Metric" (at 62.23 222.25 0)
      (effects (font (size 1.524 1.524)) (justify left) hide)
    )
    (property "Datasheet" "https://www.murata.com/products/productdetail?partno=GRM155R61H104KE14%23" (at 67.31 227.33 0)
      (effects (font (size 1.27 1.27)) hide)
    )
    (property "Manufacturer" "Murata" (at 57.15 222.25 0)
      (effects (font (size 1.524 1.524)) (justify left) hide)
    )
    (property "MPN" "GRM155R61H104KE14D" (at 59.69 222.25 0)
      (effects (font (size 1.524 1.524)) (justify left) hide)
    )
    (property "Val" "100n" (at 64.77 224.79 0)
      (effects (font (size 1.27 1.27)) (justify right))
    )
    (property "License" "Apache-2.0" (at 90.17 207.01 0)
      (effects (font (size 1.27 1.27) (thickness 0.15)) (justify left bottom) hide)
    )
    (property "Author" "Antmicro" (at 92.71 207.01 0)
      (effects (font (size 1.27 1.27) (thickness 0.15)) (justify left bottom) hide)
    )
    (property "Voltage" "50V" (at 95.25 207.01 0)
      (effects (font (size 1.27 1.27)) (justify left bottom) hide)
    )
    (property "Dielectric" "X5R" (at 97.79 207.01 0)
      (effects (font (size 1.27 1.27)) (justify left bottom) hide)
    )
    (property "Public" "False" (at 100.33 207.01 0)
      (effects (font (size 1.27 1.27)) (justify left bottom) hide)
    )
    (pin "1")
    (pin "2")
    (instances
      (project "ecp5-dc-scm"
        (path ""
          (reference "C51") (unit 1)
        )
      )
    )
  )

  (symbol (lib_id "antmicroCapacitors0402:C_100n_0402") (at 76.2 227.33 90) (unit 1)
    (in_bom yes) (on_board yes) (dnp no)
    (property "Reference" "C52" (at 73.66 219.71 0)
      (effects (font (size 1.524 1.524)) (justify right))
    )
    (property "Value" "C_100n_0402" (at 80.01 227.33 0)
      (effects (font (size 1.524 1.524)) hide)
    )
    (property "Footprint" "antmicro-footprints:C_0402_1005Metric" (at 71.12 222.25 0)
      (effects (font (size 1.524 1.524)) (justify left) hide)
    )
    (property "Datasheet" "https://www.murata.com/products/productdetail?partno=GRM155R61H104KE14%23" (at 76.2 227.33 0)
      (effects (font (size 1.27 1.27)) hide)
    )
    (property "Manufacturer" "Murata" (at 66.04 222.25 0)
      (effects (font (size 1.524 1.524)) (justify left) hide)
    )
    (property "MPN" "GRM155R61H104KE14D" (at 68.58 222.25 0)
      (effects (font (size 1.524 1.524)) (justify left) hide)
    )
    (property "Val" "100n" (at 73.66 224.79 0)
      (effects (font (size 1.27 1.27)) (justify right))
    )
    (property "License" "Apache-2.0" (at 99.06 207.01 0)
      (effects (font (size 1.27 1.27) (thickness 0.15)) (justify left bottom) hide)
    )
    (property "Author" "Antmicro" (at 101.6 207.01 0)
      (effects (font (size 1.27 1.27) (thickness 0.15)) (justify left bottom) hide)
    )
    (property "Voltage" "50V" (at 104.14 207.01 0)
      (effects (font (size 1.27 1.27)) (justify left bottom) hide)
    )
    (property "Dielectric" "X5R" (at 106.68 207.01 0)
      (effects (font (size 1.27 1.27)) (justify left bottom) hide)
    )
    (property "Public" "False" (at 109.22 207.01 0)
      (effects (font (size 1.27 1.27)) (justify left bottom) hide)
    )
    (pin "1")
    (pin "2")
    (instances
      (project "ecp5-dc-scm"
        (path ""
          (reference "C52") (unit 1)
        )
      )
    )
  )

  (symbol (lib_id "antmicropower:GND") (at 76.2 231.14 0) (mirror y) (unit 1)
    (in_bom yes) (on_board yes) (dnp no)
    (property "Reference" "#PWR031" (at 76.2 237.49 0)
      (effects (font (size 1.27 1.27)) hide)
    )
    (property "Value" "GND" (at 76.073 235.5342 0)
      (effects (font (size 1.27 1.27)))
    )
    (property "Footprint" "" (at 76.2 231.14 0)
      (effects (font (size 1.27 1.27)) hide)
    )
    (property "Datasheet" "" (at 76.2 231.14 0)
      (effects (font (size 1.27 1.27)) hide)
    )
    (property "Author" "Antmicro" (at 67.31 238.76 0)
      (effects (font (size 1.27 1.27) (thickness 0.15)) (justify left bottom) hide)
    )
    (property "License" "Apache-2.0" (at 67.31 241.3 0)
      (effects (font (size 1.27 1.27) (thickness 0.15)) (justify left bottom) hide)
    )
    (pin "1")
    (instances
      (project "ecp5-dc-scm"
        (path ""
          (reference "#PWR031") (unit 1)
        )
      )
    )
  )

  (symbol (lib_id "antmicroCapacitors0402:C_10n_0402") (at 266.7 170.18 90) (unit 1)
    (in_bom yes) (on_board yes) (dnp no) (fields_autoplaced)
    (property "Reference" "C56" (at 269.24 166.3636 90)
      (effects (font (size 1.524 1.524)) (justify right))
    )
    (property "Value" "C_10n_0402" (at 270.51 170.18 0)
      (effects (font (size 1.524 1.524)) hide)
    )
    (property "Footprint" "antmicro-footprints:C_0402_1005Metric" (at 261.62 165.1 0)
      (effects (font (size 1.524 1.524)) (justify left) hide)
    )
    (property "Datasheet" "https://www.murata.com/products/productdetail?partno=GRM155R71H103KA88%23" (at 266.7 170.18 0)
      (effects (font (size 1.27 1.27)) hide)
    )
    (property "Manufacturer" "Murata" (at 256.54 165.1 0)
      (effects (font (size 1.524 1.524)) (justify left) hide)
    )
    (property "MPN" "GRM155R71H103KA88D" (at 259.08 165.1 0)
      (effects (font (size 1.524 1.524)) (justify left) hide)
    )
    (property "Val" "10n" (at 269.24 168.9036 90)
      (effects (font (size 1.27 1.27)) (justify right))
    )
    (property "License" "Apache-2.0" (at 289.56 149.86 0)
      (effects (font (size 1.27 1.27) (thickness 0.15)) (justify left bottom) hide)
    )
    (property "Author" "Antmicro" (at 292.1 149.86 0)
      (effects (font (size 1.27 1.27) (thickness 0.15)) (justify left bottom) hide)
    )
    (property "Voltage" "50V" (at 294.64 149.86 0)
      (effects (font (size 1.27 1.27)) (justify left bottom) hide)
    )
    (property "Dielectric" "X7R" (at 297.18 149.86 0)
      (effects (font (size 1.27 1.27)) (justify left bottom) hide)
    )
    (property "Public" "False" (at 299.72 149.86 0)
      (effects (font (size 1.27 1.27)) (justify left bottom) hide)
    )
    (pin "1")
    (pin "2")
    (instances
      (project "ecp5-dc-scm"
        (path ""
          (reference "C56") (unit 1)
        )
      )
    )
  )

  (symbol (lib_id "antmicropower:GND") (at 266.7 171.45 0) (unit 1)
    (in_bom yes) (on_board yes) (dnp no)
    (property "Reference" "#PWR043" (at 266.7 177.8 0)
      (effects (font (size 1.27 1.27)) hide)
    )
    (property "Value" "GND" (at 266.827 175.8442 0)
      (effects (font (size 1.27 1.27)))
    )
    (property "Footprint" "" (at 266.7 171.45 0)
      (effects (font (size 1.27 1.27)) hide)
    )
    (property "Datasheet" "" (at 266.7 171.45 0)
      (effects (font (size 1.27 1.27)) hide)
    )
    (property "Author" "Antmicro" (at 275.59 179.07 0)
      (effects (font (size 1.27 1.27) (thickness 0.15)) (justify left bottom) hide)
    )
    (property "License" "Apache-2.0" (at 275.59 181.61 0)
      (effects (font (size 1.27 1.27) (thickness 0.15)) (justify left bottom) hide)
    )
    (pin "1")
    (instances
      (project "ecp5-dc-scm"
        (path ""
          (reference "#PWR043") (unit 1)
        )
      )
    )
  )

  (symbol (lib_id "antmicroResistors0402:R_12k_0402") (at 193.04 116.84 180) (unit 1)
    (in_bom yes) (on_board yes) (dnp no) (fields_autoplaced)
    (property "Reference" "R149" (at 190.5 110.49 0)
      (effects (font (size 1.524 1.524)))
    )
    (property "Value" "R_12k_0402" (at 193.04 113.03 0)
      (effects (font (size 1.524 1.524)) hide)
    )
    (property "Footprint" "antmicro-footprints:R_0402_1005Metric" (at 187.96 121.92 0)
      (effects (font (size 1.524 1.524)) (justify left) hide)
    )
    (property "Datasheet" "https://www.bourns.com/docs/product-datasheets/cr.pdf" (at 193.04 116.84 0)
      (effects (font (size 1.27 1.27)) hide)
    )
    (property "Manufacturer" "Bourns" (at 187.96 127 0)
      (effects (font (size 1.524 1.524)) (justify left) hide)
    )
    (property "MPN" "CR0402-FX-1202GLF" (at 187.96 124.46 0)
      (effects (font (size 1.524 1.524)) (justify left) hide)
    )
    (property "Val" "12k" (at 190.5 113.03 0)
      (effects (font (size 1.27 1.27)))
    )
    (property "License" "Apache-2.0" (at 172.72 91.44 0)
      (effects (font (size 1.27 1.27) (thickness 0.15)) (justify left bottom) hide)
    )
    (property "Author" "Antmicro" (at 172.72 88.9 0)
      (effects (font (size 1.27 1.27) (thickness 0.15)) (justify left bottom) hide)
    )
    (property "Tolerance" "1%" (at 172.72 106.68 0)
      (effects (font (size 1.27 1.27)) (justify left bottom) hide)
    )
    (property "Public" "False" (at 172.72 86.36 0)
      (effects (font (size 1.27 1.27)) (justify left bottom) hide)
    )
    (pin "1")
    (pin "2")
    (instances
      (project "ecp5-dc-scm"
        (path ""
          (reference "R149") (unit 1)
        )
      )
    )
  )

  (symbol (lib_id "antmicroCapacitors0402:C_100n_0402") (at 134.62 111.76 270) (mirror x) (unit 1)
    (in_bom yes) (on_board yes) (dnp no)
    (property "Reference" "C251" (at 132.08 107.9436 90)
      (effects (font (size 1.524 1.524)) (justify right))
    )
    (property "Value" "C_100n_0402" (at 130.81 111.76 0)
      (effects (font (size 1.524 1.524)) hide)
    )
    (property "Footprint" "antmicro-footprints:C_0402_1005Metric" (at 139.7 106.68 0)
      (effects (font (size 1.524 1.524)) (justify left) hide)
    )
    (property "Datasheet" "https://www.murata.com/products/productdetail?partno=GRM155R61H104KE14%23" (at 134.62 111.76 0)
      (effects (font (size 1.27 1.27)) hide)
    )
    (property "Manufacturer" "Murata" (at 144.78 106.68 0)
      (effects (font (size 1.524 1.524)) (justify left) hide)
    )
    (property "MPN" "GRM155R61H104KE14D" (at 142.24 106.68 0)
      (effects (font (size 1.524 1.524)) (justify left) hide)
    )
    (property "Val" "100n" (at 132.08 110.4836 90)
      (effects (font (size 1.27 1.27)) (justify right))
    )
    (property "License" "Apache-2.0" (at 111.76 91.44 0)
      (effects (font (size 1.27 1.27) (thickness 0.15)) (justify left bottom) hide)
    )
    (property "Author" "Antmicro" (at 109.22 91.44 0)
      (effects (font (size 1.27 1.27) (thickness 0.15)) (justify left bottom) hide)
    )
    (property "Voltage" "50V" (at 106.68 91.44 0)
      (effects (font (size 1.27 1.27)) (justify left bottom) hide)
    )
    (property "Dielectric" "X5R" (at 104.14 91.44 0)
      (effects (font (size 1.27 1.27)) (justify left bottom) hide)
    )
    (property "Public" "False" (at 101.6 91.44 0)
      (effects (font (size 1.27 1.27)) (justify left bottom) hide)
    )
    (pin "1")
    (pin "2")
    (instances
      (project "ecp5-dc-scm"
        (path ""
          (reference "C251") (unit 1)
        )
      )
    )
  )

  (symbol (lib_id "antmicropower:GND") (at 134.62 113.03 0) (unit 1)
    (in_bom yes) (on_board yes) (dnp no)
    (property "Reference" "#PWR0145" (at 134.62 119.38 0)
      (effects (font (size 1.27 1.27)) hide)
    )
    (property "Value" "GND" (at 134.747 117.4242 0)
      (effects (font (size 1.27 1.27)))
    )
    (property "Footprint" "" (at 134.62 113.03 0)
      (effects (font (size 1.27 1.27)) hide)
    )
    (property "Datasheet" "" (at 134.62 113.03 0)
      (effects (font (size 1.27 1.27)) hide)
    )
    (property "Author" "Antmicro" (at 143.51 120.65 0)
      (effects (font (size 1.27 1.27) (thickness 0.15)) (justify left bottom) hide)
    )
    (property "License" "Apache-2.0" (at 143.51 123.19 0)
      (effects (font (size 1.27 1.27) (thickness 0.15)) (justify left bottom) hide)
    )
    (pin "1")
    (instances
      (project "ecp5-dc-scm"
        (path ""
          (reference "#PWR0145") (unit 1)
        )
      )
    )
  )

  (symbol (lib_id "antmicropower:GND") (at 289.56 53.34 0) (mirror y) (unit 1)
    (in_bom yes) (on_board yes) (dnp no)
    (property "Reference" "#PWR0104" (at 289.56 59.69 0)
      (effects (font (size 1.27 1.27)) hide)
    )
    (property "Value" "GND" (at 289.433 57.7342 0)
      (effects (font (size 1.27 1.27)))
    )
    (property "Footprint" "" (at 289.56 53.34 0)
      (effects (font (size 1.27 1.27)) hide)
    )
    (property "Datasheet" "" (at 289.56 53.34 0)
      (effects (font (size 1.27 1.27)) hide)
    )
    (property "Author" "Antmicro" (at 280.67 60.96 0)
      (effects (font (size 1.27 1.27) (thickness 0.15)) (justify left bottom) hide)
    )
    (property "License" "Apache-2.0" (at 280.67 63.5 0)
      (effects (font (size 1.27 1.27) (thickness 0.15)) (justify left bottom) hide)
    )
    (pin "1")
    (instances
      (project "ecp5-dc-scm"
        (path ""
          (reference "#PWR0104") (unit 1)
        )
      )
    )
  )

  (symbol (lib_id "antmicropower:GND") (at 298.45 130.81 0) (mirror y) (unit 1)
    (in_bom yes) (on_board yes) (dnp no)
    (property "Reference" "#PWR0105" (at 298.45 137.16 0)
      (effects (font (size 1.27 1.27)) hide)
    )
    (property "Value" "GND" (at 298.323 135.2042 0)
      (effects (font (size 1.27 1.27)))
    )
    (property "Footprint" "" (at 298.45 130.81 0)
      (effects (font (size 1.27 1.27)) hide)
    )
    (property "Datasheet" "" (at 298.45 130.81 0)
      (effects (font (size 1.27 1.27)) hide)
    )
    (property "Author" "Antmicro" (at 289.56 138.43 0)
      (effects (font (size 1.27 1.27) (thickness 0.15)) (justify left bottom) hide)
    )
    (property "License" "Apache-2.0" (at 289.56 140.97 0)
      (effects (font (size 1.27 1.27) (thickness 0.15)) (justify left bottom) hide)
    )
    (pin "1")
    (instances
      (project "ecp5-dc-scm"
        (path ""
          (reference "#PWR0105") (unit 1)
        )
      )
    )
  )

  (symbol (lib_id "antmicropower:GND") (at 405.13 57.15 0) (mirror y) (unit 1)
    (in_bom yes) (on_board yes) (dnp no)
    (property "Reference" "#PWR0115" (at 405.13 63.5 0)
      (effects (font (size 1.27 1.27)) hide)
    )
    (property "Value" "GND" (at 405.003 61.5442 0)
      (effects (font (size 1.27 1.27)))
    )
    (property "Footprint" "" (at 405.13 57.15 0)
      (effects (font (size 1.27 1.27)) hide)
    )
    (property "Datasheet" "" (at 405.13 57.15 0)
      (effects (font (size 1.27 1.27)) hide)
    )
    (property "Author" "Antmicro" (at 396.24 64.77 0)
      (effects (font (size 1.27 1.27) (thickness 0.15)) (justify left bottom) hide)
    )
    (property "License" "Apache-2.0" (at 396.24 67.31 0)
      (effects (font (size 1.27 1.27) (thickness 0.15)) (justify left bottom) hide)
    )
    (pin "1")
    (instances
      (project "ecp5-dc-scm"
        (path ""
          (reference "#PWR0115") (unit 1)
        )
      )
    )
  )

  (symbol (lib_id "antmicroResistors0402:R_12k_0402") (at 339.09 85.09 0) (unit 1)
    (in_bom yes) (on_board yes) (dnp no) (fields_autoplaced)
    (property "Reference" "R77" (at 341.63 88.9 0)
      (effects (font (size 1.524 1.524)))
    )
    (property "Value" "R_12k_0402" (at 339.09 88.9 0)
      (effects (font (size 1.524 1.524)) hide)
    )
    (property "Footprint" "antmicro-footprints:R_0402_1005Metric" (at 344.17 80.01 0)
      (effects (font (size 1.524 1.524)) (justify left) hide)
    )
    (property "Datasheet" "https://www.bourns.com/docs/product-datasheets/cr.pdf" (at 339.09 85.09 0)
      (effects (font (size 1.27 1.27)) hide)
    )
    (property "Manufacturer" "Bourns" (at 344.17 74.93 0)
      (effects (font (size 1.524 1.524)) (justify left) hide)
    )
    (property "MPN" "CR0402-FX-1202GLF" (at 344.17 77.47 0)
      (effects (font (size 1.524 1.524)) (justify left) hide)
    )
    (property "Val" "12k" (at 341.63 91.44 0)
      (effects (font (size 1.27 1.27)))
    )
    (property "License" "Apache-2.0" (at 359.41 110.49 0)
      (effects (font (size 1.27 1.27) (thickness 0.15)) (justify left bottom) hide)
    )
    (property "Author" "Antmicro" (at 359.41 113.03 0)
      (effects (font (size 1.27 1.27) (thickness 0.15)) (justify left bottom) hide)
    )
    (property "Tolerance" "1%" (at 359.41 95.25 0)
      (effects (font (size 1.27 1.27)) (justify left bottom) hide)
    )
    (property "Public" "False" (at 359.41 115.57 0)
      (effects (font (size 1.27 1.27)) (justify left bottom) hide)
    )
    (pin "1")
    (pin "2")
    (instances
      (project "ecp5-dc-scm"
        (path ""
          (reference "R77") (unit 1)
        )
      )
    )
  )

  (symbol (lib_id "antmicroResistors0402:R_12k_0402") (at 337.82 171.45 0) (unit 1)
    (in_bom yes) (on_board yes) (dnp no) (fields_autoplaced)
    (property "Reference" "R75" (at 340.36 175.26 0)
      (effects (font (size 1.524 1.524)))
    )
    (property "Value" "R_12k_0402" (at 337.82 175.26 0)
      (effects (font (size 1.524 1.524)) hide)
    )
    (property "Footprint" "antmicro-footprints:R_0402_1005Metric" (at 342.9 166.37 0)
      (effects (font (size 1.524 1.524)) (justify left) hide)
    )
    (property "Datasheet" "https://www.bourns.com/docs/product-datasheets/cr.pdf" (at 337.82 171.45 0)
      (effects (font (size 1.27 1.27)) hide)
    )
    (property "Manufacturer" "Bourns" (at 342.9 161.29 0)
      (effects (font (size 1.524 1.524)) (justify left) hide)
    )
    (property "MPN" "CR0402-FX-1202GLF" (at 342.9 163.83 0)
      (effects (font (size 1.524 1.524)) (justify left) hide)
    )
    (property "Val" "12k" (at 340.36 177.8 0)
      (effects (font (size 1.27 1.27)))
    )
    (property "License" "Apache-2.0" (at 358.14 196.85 0)
      (effects (font (size 1.27 1.27) (thickness 0.15)) (justify left bottom) hide)
    )
    (property "Author" "Antmicro" (at 358.14 199.39 0)
      (effects (font (size 1.27 1.27) (thickness 0.15)) (justify left bottom) hide)
    )
    (property "Tolerance" "1%" (at 358.14 181.61 0)
      (effects (font (size 1.27 1.27)) (justify left bottom) hide)
    )
    (property "Public" "False" (at 358.14 201.93 0)
      (effects (font (size 1.27 1.27)) (justify left bottom) hide)
    )
    (pin "1")
    (pin "2")
    (instances
      (project "ecp5-dc-scm"
        (path ""
          (reference "R75") (unit 1)
        )
      )
    )
  )

  (symbol (lib_id "antmicroLogicTranslatorsLevelShifters:NVT2008BQ,115") (at 120.65 170.18 0) (mirror y) (unit 1)
    (in_bom yes) (on_board yes) (dnp no) (fields_autoplaced)
    (property "Reference" "U7" (at 110.49 162.56 0)
      (effects (font (size 1.27 1.27)))
    )
    (property "Value" "NVT2008BQ,115" (at 110.49 165.1 0)
      (effects (font (size 1.27 1.27)))
    )
    (property "Footprint" "antmicro-footprints:VQFN-20_1EP_4.5x2.5mm_P0.5mm" (at 102.87 151.13 0)
      (effects (font (size 1.27 1.27)) hide)
    )
    (property "Datasheet" "https://www.nxp.com/docs/en/data-sheet/NVT2008_NVT2010.pdf" (at 104.14 151.13 0)
      (effects (font (size 1.27 1.27)) hide)
    )
    (property "MPN" "NVT2008BQ,115" (at 113.03 148.59 0)
      (effects (font (size 1.27 1.27)) hide)
    )
    (property "Manufacturer" "NXP" (at 110.49 146.05 0)
      (effects (font (size 1.27 1.27)) hide)
    )
    (property "Author" "Antmicro" (at 85.09 187.96 0)
      (effects (font (size 1.27 1.27) (thickness 0.15)) (justify left bottom) hide)
    )
    (property "License" "Apache-2.0" (at 85.09 190.5 0)
      (effects (font (size 1.27 1.27) (thickness 0.15)) (justify left bottom) hide)
    )
    (pin "1")
    (pin "10")
    (pin "11")
    (pin "12")
    (pin "13")
    (pin "14")
    (pin "15")
    (pin "16")
    (pin "17")
    (pin "18")
    (pin "19")
    (pin "2")
    (pin "20")
    (pin "3")
    (pin "4")
    (pin "5")
    (pin "6")
    (pin "7")
    (pin "8")
    (pin "9")
    (pin "21")
    (instances
      (project "ecp5-dc-scm"
        (path ""
          (reference "U7") (unit 1)
        )
      )
    )
  )

  (symbol (lib_id "antmicropower:GND") (at 121.92 204.47 0) (unit 1)
    (in_bom yes) (on_board yes) (dnp no)
    (property "Reference" "#PWR035" (at 121.92 210.82 0)
      (effects (font (size 1.27 1.27)) hide)
    )
    (property "Value" "GND" (at 122.047 208.8642 0)
      (effects (font (size 1.27 1.27)))
    )
    (property "Footprint" "" (at 121.92 204.47 0)
      (effects (font (size 1.27 1.27)) hide)
    )
    (property "Datasheet" "" (at 121.92 204.47 0)
      (effects (font (size 1.27 1.27)) hide)
    )
    (property "Author" "Antmicro" (at 130.81 212.09 0)
      (effects (font (size 1.27 1.27) (thickness 0.15)) (justify left bottom) hide)
    )
    (property "License" "Apache-2.0" (at 130.81 214.63 0)
      (effects (font (size 1.27 1.27) (thickness 0.15)) (justify left bottom) hide)
    )
    (pin "1")
    (instances
      (project "ecp5-dc-scm"
        (path ""
          (reference "#PWR035") (unit 1)
        )
      )
    )
  )

  (symbol (lib_id "antmicroResistors0402:R_357k_0402") (at 60.96 180.34 270) (unit 1)
    (in_bom yes) (on_board yes) (dnp no)
    (property "Reference" "R50" (at 59.69 176.53 0)
      (effects (font (size 1.524 1.524)) (justify left))
    )
    (property "Value" "R_357k_0402" (at 57.15 180.34 0)
      (effects (font (size 1.524 1.524)) hide)
    )
    (property "Footprint" "antmicro-footprints:R_0402_1005Metric" (at 66.04 185.42 0)
      (effects (font (size 1.524 1.524)) (justify left) hide)
    )
    (property "Datasheet" "https://www.bourns.com/docs/product-datasheets/cr.pdf" (at 60.96 180.34 0)
      (effects (font (size 1.27 1.27)) hide)
    )
    (property "Manufacturer" "Bourns" (at 71.12 185.42 0)
      (effects (font (size 1.524 1.524)) (justify left) hide)
    )
    (property "MPN" "CR0402-FX-3573GLF" (at 68.58 185.42 0)
      (effects (font (size 1.524 1.524)) (justify left) hide)
    )
    (property "Val" "357k" (at 59.69 185.42 0)
      (effects (font (size 1.27 1.27)) (justify left))
    )
    (property "License" "Apache-2.0" (at 35.56 200.66 0)
      (effects (font (size 1.27 1.27) (thickness 0.15)) (justify left bottom) hide)
    )
    (property "Author" "Antmicro" (at 33.02 200.66 0)
      (effects (font (size 1.27 1.27) (thickness 0.15)) (justify left bottom) hide)
    )
    (property "Tolerance" "1%" (at 50.8 200.66 0)
      (effects (font (size 1.27 1.27)) (justify left bottom) hide)
    )
    (property "Public" "False" (at 30.48 200.66 0)
      (effects (font (size 1.27 1.27)) (justify left bottom) hide)
    )
    (pin "1")
    (pin "2")
    (instances
      (project "ecp5-dc-scm"
        (path ""
          (reference "R50") (unit 1)
        )
      )
    )
  )

  (symbol (lib_id "antmicroResistors0402:R_357k_0402") (at 58.42 171.45 270) (unit 1)
    (in_bom yes) (on_board yes) (dnp no)
    (property "Reference" "R49" (at 55.88 172.72 0)
      (effects (font (size 1.524 1.524)) (justify right))
    )
    (property "Value" "R_357k_0402" (at 54.61 171.45 0)
      (effects (font (size 1.524 1.524)) hide)
    )
    (property "Footprint" "antmicro-footprints:R_0402_1005Metric" (at 63.5 176.53 0)
      (effects (font (size 1.524 1.524)) (justify left) hide)
    )
    (property "Datasheet" "https://www.bourns.com/docs/product-datasheets/cr.pdf" (at 58.42 171.45 0)
      (effects (font (size 1.27 1.27)) hide)
    )
    (property "Manufacturer" "Bourns" (at 68.58 176.53 0)
      (effects (font (size 1.524 1.524)) (justify left) hide)
    )
    (property "MPN" "CR0402-FX-3573GLF" (at 66.04 176.53 0)
      (effects (font (size 1.524 1.524)) (justify left) hide)
    )
    (property "Val" "357k" (at 57.15 181.61 0)
      (effects (font (size 1.27 1.27)) (justify right))
    )
    (property "License" "Apache-2.0" (at 33.02 191.77 0)
      (effects (font (size 1.27 1.27) (thickness 0.15)) (justify left bottom) hide)
    )
    (property "Author" "Antmicro" (at 30.48 191.77 0)
      (effects (font (size 1.27 1.27) (thickness 0.15)) (justify left bottom) hide)
    )
    (property "Tolerance" "1%" (at 48.26 191.77 0)
      (effects (font (size 1.27 1.27)) (justify left bottom) hide)
    )
    (property "Public" "False" (at 27.94 191.77 0)
      (effects (font (size 1.27 1.27)) (justify left bottom) hide)
    )
    (pin "1")
    (pin "2")
    (instances
      (project "ecp5-dc-scm"
        (path ""
          (reference "R49") (unit 1)
        )
      )
    )
  )

  (symbol (lib_id "antmicroResistors0402:R_357k_0402") (at 63.5 171.45 270) (unit 1)
    (in_bom yes) (on_board yes) (dnp no)
    (property "Reference" "R51" (at 62.23 167.64 0)
      (effects (font (size 1.524 1.524)) (justify left))
    )
    (property "Value" "R_357k_0402" (at 59.69 171.45 0)
      (effects (font (size 1.524 1.524)) hide)
    )
    (property "Footprint" "antmicro-footprints:R_0402_1005Metric" (at 68.58 176.53 0)
      (effects (font (size 1.524 1.524)) (justify left) hide)
    )
    (property "Datasheet" "https://www.bourns.com/docs/product-datasheets/cr.pdf" (at 63.5 171.45 0)
      (effects (font (size 1.27 1.27)) hide)
    )
    (property "Manufacturer" "Bourns" (at 73.66 176.53 0)
      (effects (font (size 1.524 1.524)) (justify left) hide)
    )
    (property "MPN" "CR0402-FX-3573GLF" (at 71.12 176.53 0)
      (effects (font (size 1.524 1.524)) (justify left) hide)
    )
    (property "Val" "357k" (at 62.23 176.53 0)
      (effects (font (size 1.27 1.27)) (justify left))
    )
    (property "License" "Apache-2.0" (at 38.1 191.77 0)
      (effects (font (size 1.27 1.27) (thickness 0.15)) (justify left bottom) hide)
    )
    (property "Author" "Antmicro" (at 35.56 191.77 0)
      (effects (font (size 1.27 1.27) (thickness 0.15)) (justify left bottom) hide)
    )
    (property "Tolerance" "1%" (at 53.34 191.77 0)
      (effects (font (size 1.27 1.27)) (justify left bottom) hide)
    )
    (property "Public" "False" (at 33.02 191.77 0)
      (effects (font (size 1.27 1.27)) (justify left bottom) hide)
    )
    (pin "1")
    (pin "2")
    (instances
      (project "ecp5-dc-scm"
        (path ""
          (reference "R51") (unit 1)
        )
      )
    )
  )

  (symbol (lib_id "antmicroResistors0402:R_357k_0402") (at 66.04 180.34 270) (unit 1)
    (in_bom yes) (on_board yes) (dnp no)
    (property "Reference" "R52" (at 64.77 176.53 0)
      (effects (font (size 1.524 1.524)) (justify left))
    )
    (property "Value" "R_357k_0402" (at 62.23 180.34 0)
      (effects (font (size 1.524 1.524)) hide)
    )
    (property "Footprint" "antmicro-footprints:R_0402_1005Metric" (at 71.12 185.42 0)
      (effects (font (size 1.524 1.524)) (justify left) hide)
    )
    (property "Datasheet" "https://www.bourns.com/docs/product-datasheets/cr.pdf" (at 66.04 180.34 0)
      (effects (font (size 1.27 1.27)) hide)
    )
    (property "Manufacturer" "Bourns" (at 76.2 185.42 0)
      (effects (font (size 1.524 1.524)) (justify left) hide)
    )
    (property "MPN" "CR0402-FX-3573GLF" (at 73.66 185.42 0)
      (effects (font (size 1.524 1.524)) (justify left) hide)
    )
    (property "Val" "357k" (at 64.77 185.42 0)
      (effects (font (size 1.27 1.27)) (justify left))
    )
    (property "License" "Apache-2.0" (at 40.64 200.66 0)
      (effects (font (size 1.27 1.27) (thickness 0.15)) (justify left bottom) hide)
    )
    (property "Author" "Antmicro" (at 38.1 200.66 0)
      (effects (font (size 1.27 1.27) (thickness 0.15)) (justify left bottom) hide)
    )
    (property "Tolerance" "1%" (at 55.88 200.66 0)
      (effects (font (size 1.27 1.27)) (justify left bottom) hide)
    )
    (property "Public" "False" (at 35.56 200.66 0)
      (effects (font (size 1.27 1.27)) (justify left bottom) hide)
    )
    (pin "1")
    (pin "2")
    (instances
      (project "ecp5-dc-scm"
        (path ""
          (reference "R52") (unit 1)
        )
      )
    )
  )

  (symbol (lib_id "antmicroResistors0402:R_357k_0402") (at 68.58 171.45 270) (unit 1)
    (in_bom yes) (on_board yes) (dnp no)
    (property "Reference" "R53" (at 67.31 167.64 0)
      (effects (font (size 1.524 1.524)) (justify left))
    )
    (property "Value" "R_357k_0402" (at 64.77 171.45 0)
      (effects (font (size 1.524 1.524)) hide)
    )
    (property "Footprint" "antmicro-footprints:R_0402_1005Metric" (at 73.66 176.53 0)
      (effects (font (size 1.524 1.524)) (justify left) hide)
    )
    (property "Datasheet" "https://www.bourns.com/docs/product-datasheets/cr.pdf" (at 68.58 171.45 0)
      (effects (font (size 1.27 1.27)) hide)
    )
    (property "Manufacturer" "Bourns" (at 78.74 176.53 0)
      (effects (font (size 1.524 1.524)) (justify left) hide)
    )
    (property "MPN" "CR0402-FX-3573GLF" (at 76.2 176.53 0)
      (effects (font (size 1.524 1.524)) (justify left) hide)
    )
    (property "Val" "357k" (at 67.31 176.53 0)
      (effects (font (size 1.27 1.27)) (justify left))
    )
    (property "License" "Apache-2.0" (at 43.18 191.77 0)
      (effects (font (size 1.27 1.27) (thickness 0.15)) (justify left bottom) hide)
    )
    (property "Author" "Antmicro" (at 40.64 191.77 0)
      (effects (font (size 1.27 1.27) (thickness 0.15)) (justify left bottom) hide)
    )
    (property "Tolerance" "1%" (at 58.42 191.77 0)
      (effects (font (size 1.27 1.27)) (justify left bottom) hide)
    )
    (property "Public" "False" (at 38.1 191.77 0)
      (effects (font (size 1.27 1.27)) (justify left bottom) hide)
    )
    (pin "1")
    (pin "2")
    (instances
      (project "ecp5-dc-scm"
        (path ""
          (reference "R53") (unit 1)
        )
      )
    )
  )

  (symbol (lib_id "antmicroResistors0402:R_357k_0402") (at 71.12 180.34 270) (unit 1)
    (in_bom yes) (on_board yes) (dnp no)
    (property "Reference" "R54" (at 69.85 176.53 0)
      (effects (font (size 1.524 1.524)) (justify left))
    )
    (property "Value" "R_357k_0402" (at 67.31 180.34 0)
      (effects (font (size 1.524 1.524)) hide)
    )
    (property "Footprint" "antmicro-footprints:R_0402_1005Metric" (at 76.2 185.42 0)
      (effects (font (size 1.524 1.524)) (justify left) hide)
    )
    (property "Datasheet" "https://www.bourns.com/docs/product-datasheets/cr.pdf" (at 71.12 180.34 0)
      (effects (font (size 1.27 1.27)) hide)
    )
    (property "Manufacturer" "Bourns" (at 81.28 185.42 0)
      (effects (font (size 1.524 1.524)) (justify left) hide)
    )
    (property "MPN" "CR0402-FX-3573GLF" (at 78.74 185.42 0)
      (effects (font (size 1.524 1.524)) (justify left) hide)
    )
    (property "Val" "357k" (at 69.85 185.42 0)
      (effects (font (size 1.27 1.27)) (justify left))
    )
    (property "License" "Apache-2.0" (at 45.72 200.66 0)
      (effects (font (size 1.27 1.27) (thickness 0.15)) (justify left bottom) hide)
    )
    (property "Author" "Antmicro" (at 43.18 200.66 0)
      (effects (font (size 1.27 1.27) (thickness 0.15)) (justify left bottom) hide)
    )
    (property "Tolerance" "1%" (at 60.96 200.66 0)
      (effects (font (size 1.27 1.27)) (justify left bottom) hide)
    )
    (property "Public" "False" (at 40.64 200.66 0)
      (effects (font (size 1.27 1.27)) (justify left bottom) hide)
    )
    (pin "1")
    (pin "2")
    (instances
      (project "ecp5-dc-scm"
        (path ""
          (reference "R54") (unit 1)
        )
      )
    )
  )

  (symbol (lib_id "antmicroResistors0402:R_357k_0402") (at 73.66 171.45 270) (unit 1)
    (in_bom yes) (on_board yes) (dnp no)
    (property "Reference" "R55" (at 72.39 167.64 0)
      (effects (font (size 1.524 1.524)) (justify left))
    )
    (property "Value" "R_357k_0402" (at 69.85 171.45 0)
      (effects (font (size 1.524 1.524)) hide)
    )
    (property "Footprint" "antmicro-footprints:R_0402_1005Metric" (at 78.74 176.53 0)
      (effects (font (size 1.524 1.524)) (justify left) hide)
    )
    (property "Datasheet" "https://www.bourns.com/docs/product-datasheets/cr.pdf" (at 73.66 171.45 0)
      (effects (font (size 1.27 1.27)) hide)
    )
    (property "Manufacturer" "Bourns" (at 83.82 176.53 0)
      (effects (font (size 1.524 1.524)) (justify left) hide)
    )
    (property "MPN" "CR0402-FX-3573GLF" (at 81.28 176.53 0)
      (effects (font (size 1.524 1.524)) (justify left) hide)
    )
    (property "Val" "357k" (at 72.39 176.53 0)
      (effects (font (size 1.27 1.27)) (justify left))
    )
    (property "License" "Apache-2.0" (at 48.26 191.77 0)
      (effects (font (size 1.27 1.27) (thickness 0.15)) (justify left bottom) hide)
    )
    (property "Author" "Antmicro" (at 45.72 191.77 0)
      (effects (font (size 1.27 1.27) (thickness 0.15)) (justify left bottom) hide)
    )
    (property "Tolerance" "1%" (at 63.5 191.77 0)
      (effects (font (size 1.27 1.27)) (justify left bottom) hide)
    )
    (property "Public" "False" (at 43.18 191.77 0)
      (effects (font (size 1.27 1.27)) (justify left bottom) hide)
    )
    (pin "1")
    (pin "2")
    (instances
      (project "ecp5-dc-scm"
        (path ""
          (reference "R55") (unit 1)
        )
      )
    )
  )

  (symbol (lib_id "antmicroResistors0402:R_357k_0402") (at 76.2 180.34 270) (unit 1)
    (in_bom yes) (on_board yes) (dnp no)
    (property "Reference" "R56" (at 74.93 176.53 0)
      (effects (font (size 1.524 1.524)) (justify left))
    )
    (property "Value" "R_357k_0402" (at 72.39 180.34 0)
      (effects (font (size 1.524 1.524)) hide)
    )
    (property "Footprint" "antmicro-footprints:R_0402_1005Metric" (at 81.28 185.42 0)
      (effects (font (size 1.524 1.524)) (justify left) hide)
    )
    (property "Datasheet" "https://www.bourns.com/docs/product-datasheets/cr.pdf" (at 76.2 180.34 0)
      (effects (font (size 1.27 1.27)) hide)
    )
    (property "Manufacturer" "Bourns" (at 86.36 185.42 0)
      (effects (font (size 1.524 1.524)) (justify left) hide)
    )
    (property "MPN" "CR0402-FX-3573GLF" (at 83.82 185.42 0)
      (effects (font (size 1.524 1.524)) (justify left) hide)
    )
    (property "Val" "357k" (at 74.93 185.42 0)
      (effects (font (size 1.27 1.27)) (justify left))
    )
    (property "License" "Apache-2.0" (at 50.8 200.66 0)
      (effects (font (size 1.27 1.27) (thickness 0.15)) (justify left bottom) hide)
    )
    (property "Author" "Antmicro" (at 48.26 200.66 0)
      (effects (font (size 1.27 1.27) (thickness 0.15)) (justify left bottom) hide)
    )
    (property "Tolerance" "1%" (at 66.04 200.66 0)
      (effects (font (size 1.27 1.27)) (justify left bottom) hide)
    )
    (property "Public" "False" (at 45.72 200.66 0)
      (effects (font (size 1.27 1.27)) (justify left bottom) hide)
    )
    (pin "1")
    (pin "2")
    (instances
      (project "ecp5-dc-scm"
        (path ""
          (reference "R56") (unit 1)
        )
      )
    )
  )

  (symbol (lib_id "antmicroResistors0402:R_200k_0402") (at 83.82 161.29 0) (unit 1)
    (in_bom yes) (on_board yes) (dnp no) (fields_autoplaced)
    (property "Reference" "R57" (at 86.36 154.94 0)
      (effects (font (size 1.524 1.524)))
    )
    (property "Value" "R_200k_0402" (at 83.82 165.1 0)
      (effects (font (size 1.524 1.524)) hide)
    )
    (property "Footprint" "antmicro-footprints:R_0402_1005Metric" (at 88.9 156.21 0)
      (effects (font (size 1.524 1.524)) (justify left) hide)
    )
    (property "Datasheet" "https://www.bourns.com/docs/product-datasheets/cr.pdf" (at 83.82 161.29 0)
      (effects (font (size 1.27 1.27)) hide)
    )
    (property "Manufacturer" "Bourns" (at 88.9 151.13 0)
      (effects (font (size 1.524 1.524)) (justify left) hide)
    )
    (property "MPN" "CR0402-FX-2003GLF" (at 88.9 153.67 0)
      (effects (font (size 1.524 1.524)) (justify left) hide)
    )
    (property "Val" "200k" (at 86.36 157.48 0)
      (effects (font (size 1.27 1.27)))
    )
    (property "License" "Apache-2.0" (at 104.14 186.69 0)
      (effects (font (size 1.27 1.27) (thickness 0.15)) (justify left bottom) hide)
    )
    (property "Author" "Antmicro" (at 104.14 189.23 0)
      (effects (font (size 1.27 1.27) (thickness 0.15)) (justify left bottom) hide)
    )
    (property "Tolerance" "1%" (at 104.14 171.45 0)
      (effects (font (size 1.27 1.27)) (justify left bottom) hide)
    )
    (property "Public" "False" (at 104.14 191.77 0)
      (effects (font (size 1.27 1.27)) (justify left bottom) hide)
    )
    (pin "1")
    (pin "2")
    (instances
      (project "ecp5-dc-scm"
        (path ""
          (reference "R57") (unit 1)
        )
      )
    )
  )

  (symbol (lib_id "antmicroCapacitors0402:C_100n_0402") (at 91.44 167.64 270) (mirror x) (unit 1)
    (in_bom yes) (on_board yes) (dnp no)
    (property "Reference" "C55" (at 88.9 165.1 90)
      (effects (font (size 1.524 1.524)) (justify right))
    )
    (property "Value" "C_100n_0402" (at 87.63 167.64 0)
      (effects (font (size 1.524 1.524)) hide)
    )
    (property "Footprint" "antmicro-footprints:C_0402_1005Metric" (at 96.52 162.56 0)
      (effects (font (size 1.524 1.524)) (justify left) hide)
    )
    (property "Datasheet" "https://www.murata.com/products/productdetail?partno=GRM155R61H104KE14%23" (at 91.44 167.64 0)
      (effects (font (size 1.27 1.27)) hide)
    )
    (property "Manufacturer" "Murata" (at 101.6 162.56 0)
      (effects (font (size 1.524 1.524)) (justify left) hide)
    )
    (property "MPN" "GRM155R61H104KE14D" (at 99.06 162.56 0)
      (effects (font (size 1.524 1.524)) (justify left) hide)
    )
    (property "Val" "100n" (at 88.9 167.64 90)
      (effects (font (size 1.27 1.27)) (justify right))
    )
    (property "License" "Apache-2.0" (at 68.58 147.32 0)
      (effects (font (size 1.27 1.27) (thickness 0.15)) (justify left bottom) hide)
    )
    (property "Author" "Antmicro" (at 66.04 147.32 0)
      (effects (font (size 1.27 1.27) (thickness 0.15)) (justify left bottom) hide)
    )
    (property "Voltage" "50V" (at 63.5 147.32 0)
      (effects (font (size 1.27 1.27)) (justify left bottom) hide)
    )
    (property "Dielectric" "X5R" (at 60.96 147.32 0)
      (effects (font (size 1.27 1.27)) (justify left bottom) hide)
    )
    (property "Public" "False" (at 58.42 147.32 0)
      (effects (font (size 1.27 1.27)) (justify left bottom) hide)
    )
    (pin "1")
    (pin "2")
    (instances
      (project "ecp5-dc-scm"
        (path ""
          (reference "C55") (unit 1)
        )
      )
    )
  )

  (symbol (lib_id "antmicropower:GND") (at 91.44 168.91 0) (unit 1)
    (in_bom yes) (on_board yes) (dnp no)
    (property "Reference" "#PWR036" (at 91.44 175.26 0)
      (effects (font (size 1.27 1.27)) hide)
    )
    (property "Value" "GND" (at 91.567 173.3042 0)
      (effects (font (size 1.27 1.27)))
    )
    (property "Footprint" "" (at 91.44 168.91 0)
      (effects (font (size 1.27 1.27)) hide)
    )
    (property "Datasheet" "" (at 91.44 168.91 0)
      (effects (font (size 1.27 1.27)) hide)
    )
    (property "Author" "Antmicro" (at 100.33 176.53 0)
      (effects (font (size 1.27 1.27) (thickness 0.15)) (justify left bottom) hide)
    )
    (property "License" "Apache-2.0" (at 100.33 179.07 0)
      (effects (font (size 1.27 1.27) (thickness 0.15)) (justify left bottom) hide)
    )
    (pin "1")
    (instances
      (project "ecp5-dc-scm"
        (path ""
          (reference "#PWR036") (unit 1)
        )
      )
    )
  )

  (symbol (lib_id "antmicroTransistorsFETsMOSFETsSingle:2N7002_SOT-23-3") (at 234.95 217.17 270) (unit 1)
    (in_bom yes) (on_board yes) (dnp no)
    (property "Reference" "Q1" (at 227.965 219.075 90)
      (effects (font (size 1.524 1.524)))
    )
    (property "Value" "2N7002_SOT-23-3" (at 218.44 221.615 90)
      (effects (font (size 1.524 1.524)))
    )
    (property "Footprint" "antmicro-footprints:SOT-23-3" (at 240.03 222.25 0)
      (effects (font (size 1.524 1.524)) (justify left) hide)
    )
    (property "Datasheet" "https://www.onsemi.com/pub/Collateral/NDS7002A-D.PDF" (at 242.57 222.25 0)
      (effects (font (size 1.524 1.524)) (justify left) hide)
    )
    (property "MPN" "2N7002" (at 247.65 222.25 0)
      (effects (font (size 1.524 1.524)) (justify left) hide)
    )
    (property "Manufacturer" "ON Semiconductor" (at 262.89 222.25 0)
      (effects (font (size 1.524 1.524)) (justify left) hide)
    )
    (property "Author" "Antmicro" (at 214.63 240.03 0)
      (effects (font (size 1.27 1.27) (thickness 0.15)) (justify left bottom) hide)
    )
    (property "License" "Apache-2.0" (at 212.09 240.03 0)
      (effects (font (size 1.27 1.27) (thickness 0.15)) (justify left bottom) hide)
    )
    (pin "1")
    (pin "2")
    (pin "3")
    (instances
      (project "ecp5-dc-scm"
        (path ""
          (reference "Q1") (unit 1)
        )
      )
    )
  )

  (symbol (lib_id "antmicroResistors0402:R_1k1_0402") (at 255.27 224.79 0) (unit 1)
    (in_bom yes) (on_board yes) (dnp no) (fields_autoplaced)
    (property "Reference" "R69" (at 257.81 218.44 0)
      (effects (font (size 1.524 1.524)))
    )
    (property "Value" "R_1k1_0402" (at 255.27 228.6 0)
      (effects (font (size 1.524 1.524)) hide)
    )
    (property "Footprint" "antmicro-footprints:R_0402_1005Metric" (at 260.35 219.71 0)
      (effects (font (size 1.524 1.524)) (justify left) hide)
    )
    (property "Datasheet" "https://www.bourns.com/docs/product-datasheets/cr.pdf" (at 255.27 224.79 0)
      (effects (font (size 1.27 1.27)) hide)
    )
    (property "Manufacturer" "Bourns" (at 260.35 214.63 0)
      (effects (font (size 1.524 1.524)) (justify left) hide)
    )
    (property "MPN" "CR0402-FX-1101GLF" (at 260.35 217.17 0)
      (effects (font (size 1.524 1.524)) (justify left) hide)
    )
    (property "Val" "1k1" (at 257.81 220.98 0)
      (effects (font (size 1.27 1.27)))
    )
    (property "License" "Apache-2.0" (at 275.59 250.19 0)
      (effects (font (size 1.27 1.27) (thickness 0.15)) (justify left bottom) hide)
    )
    (property "Author" "Antmicro" (at 275.59 252.73 0)
      (effects (font (size 1.27 1.27) (thickness 0.15)) (justify left bottom) hide)
    )
    (property "Tolerance" "1%" (at 275.59 234.95 0)
      (effects (font (size 1.27 1.27)) (justify left bottom) hide)
    )
    (property "Public" "False" (at 275.59 255.27 0)
      (effects (font (size 1.27 1.27)) (justify left bottom) hide)
    )
    (pin "1")
    (pin "2")
    (instances
      (project "ecp5-dc-scm"
        (path ""
          (reference "R69") (unit 1)
        )
      )
    )
  )

  (symbol (lib_id "antmicropower:GND") (at 224.79 227.33 0) (unit 1)
    (in_bom yes) (on_board yes) (dnp no)
    (property "Reference" "#PWR038" (at 224.79 233.68 0)
      (effects (font (size 1.27 1.27)) hide)
    )
    (property "Value" "GND" (at 224.917 231.7242 0)
      (effects (font (size 1.27 1.27)))
    )
    (property "Footprint" "" (at 224.79 227.33 0)
      (effects (font (size 1.27 1.27)) hide)
    )
    (property "Datasheet" "" (at 224.79 227.33 0)
      (effects (font (size 1.27 1.27)) hide)
    )
    (property "Author" "Antmicro" (at 233.68 234.95 0)
      (effects (font (size 1.27 1.27) (thickness 0.15)) (justify left bottom) hide)
    )
    (property "License" "Apache-2.0" (at 233.68 237.49 0)
      (effects (font (size 1.27 1.27) (thickness 0.15)) (justify left bottom) hide)
    )
    (pin "1")
    (instances
      (project "ecp5-dc-scm"
        (path ""
          (reference "#PWR038") (unit 1)
        )
      )
    )
  )

  (symbol (lib_id "antmicroTransistorsFETsMOSFETsSingle:2N7002_SOT-23-3") (at 234.95 241.3 270) (unit 1)
    (in_bom yes) (on_board yes) (dnp no)
    (property "Reference" "Q2" (at 229.235 241.935 90)
      (effects (font (size 1.524 1.524)))
    )
    (property "Value" "2N7002_SOT-23-3" (at 219.71 245.11 90)
      (effects (font (size 1.524 1.524)))
    )
    (property "Footprint" "antmicro-footprints:SOT-23-3" (at 240.03 246.38 0)
      (effects (font (size 1.524 1.524)) (justify left) hide)
    )
    (property "Datasheet" "https://www.onsemi.com/pub/Collateral/NDS7002A-D.PDF" (at 242.57 246.38 0)
      (effects (font (size 1.524 1.524)) (justify left) hide)
    )
    (property "MPN" "2N7002" (at 247.65 246.38 0)
      (effects (font (size 1.524 1.524)) (justify left) hide)
    )
    (property "Manufacturer" "ON Semiconductor" (at 262.89 246.38 0)
      (effects (font (size 1.524 1.524)) (justify left) hide)
    )
    (property "Author" "Antmicro" (at 214.63 264.16 0)
      (effects (font (size 1.27 1.27) (thickness 0.15)) (justify left bottom) hide)
    )
    (property "License" "Apache-2.0" (at 212.09 264.16 0)
      (effects (font (size 1.27 1.27) (thickness 0.15)) (justify left bottom) hide)
    )
    (pin "1")
    (pin "2")
    (pin "3")
    (instances
      (project "ecp5-dc-scm"
        (path ""
          (reference "Q2") (unit 1)
        )
      )
    )
  )

  (symbol (lib_id "antmicroResistors0402:R_1k1_0402") (at 255.27 248.92 0) (unit 1)
    (in_bom yes) (on_board yes) (dnp no) (fields_autoplaced)
    (property "Reference" "R70" (at 257.81 242.57 0)
      (effects (font (size 1.524 1.524)))
    )
    (property "Value" "R_1k1_0402" (at 255.27 252.73 0)
      (effects (font (size 1.524 1.524)) hide)
    )
    (property "Footprint" "antmicro-footprints:R_0402_1005Metric" (at 260.35 243.84 0)
      (effects (font (size 1.524 1.524)) (justify left) hide)
    )
    (property "Datasheet" "https://www.bourns.com/docs/product-datasheets/cr.pdf" (at 255.27 248.92 0)
      (effects (font (size 1.27 1.27)) hide)
    )
    (property "Manufacturer" "Bourns" (at 260.35 238.76 0)
      (effects (font (size 1.524 1.524)) (justify left) hide)
    )
    (property "MPN" "CR0402-FX-1101GLF" (at 260.35 241.3 0)
      (effects (font (size 1.524 1.524)) (justify left) hide)
    )
    (property "Val" "1k1" (at 257.81 245.11 0)
      (effects (font (size 1.27 1.27)))
    )
    (property "License" "Apache-2.0" (at 275.59 274.32 0)
      (effects (font (size 1.27 1.27) (thickness 0.15)) (justify left bottom) hide)
    )
    (property "Author" "Antmicro" (at 275.59 276.86 0)
      (effects (font (size 1.27 1.27) (thickness 0.15)) (justify left bottom) hide)
    )
    (property "Tolerance" "1%" (at 275.59 259.08 0)
      (effects (font (size 1.27 1.27)) (justify left bottom) hide)
    )
    (property "Public" "False" (at 275.59 279.4 0)
      (effects (font (size 1.27 1.27)) (justify left bottom) hide)
    )
    (pin "1")
    (pin "2")
    (instances
      (project "ecp5-dc-scm"
        (path ""
          (reference "R70") (unit 1)
        )
      )
    )
  )

  (symbol (lib_id "antmicropower:GND") (at 226.06 251.46 0) (unit 1)
    (in_bom yes) (on_board yes) (dnp no)
    (property "Reference" "#PWR039" (at 226.06 257.81 0)
      (effects (font (size 1.27 1.27)) hide)
    )
    (property "Value" "GND" (at 226.187 255.8542 0)
      (effects (font (size 1.27 1.27)))
    )
    (property "Footprint" "" (at 226.06 251.46 0)
      (effects (font (size 1.27 1.27)) hide)
    )
    (property "Datasheet" "" (at 226.06 251.46 0)
      (effects (font (size 1.27 1.27)) hide)
    )
    (property "Author" "Antmicro" (at 234.95 259.08 0)
      (effects (font (size 1.27 1.27) (thickness 0.15)) (justify left bottom) hide)
    )
    (property "License" "Apache-2.0" (at 234.95 261.62 0)
      (effects (font (size 1.27 1.27) (thickness 0.15)) (justify left bottom) hide)
    )
    (pin "1")
    (instances
      (project "ecp5-dc-scm"
        (path ""
          (reference "#PWR039") (unit 1)
        )
      )
    )
  )

  (symbol (lib_id "antmicroTransistorsFETsMOSFETsSingle:2N7002_SOT-23-3") (at 234.95 262.89 270) (unit 1)
    (in_bom yes) (on_board yes) (dnp no)
    (property "Reference" "Q3" (at 229.235 265.43 90)
      (effects (font (size 1.524 1.524)))
    )
    (property "Value" "2N7002_SOT-23-3" (at 219.71 267.97 90)
      (effects (font (size 1.524 1.524)))
    )
    (property "Footprint" "antmicro-footprints:SOT-23-3" (at 240.03 267.97 0)
      (effects (font (size 1.524 1.524)) (justify left) hide)
    )
    (property "Datasheet" "https://www.onsemi.com/pub/Collateral/NDS7002A-D.PDF" (at 242.57 267.97 0)
      (effects (font (size 1.524 1.524)) (justify left) hide)
    )
    (property "MPN" "2N7002" (at 247.65 267.97 0)
      (effects (font (size 1.524 1.524)) (justify left) hide)
    )
    (property "Manufacturer" "ON Semiconductor" (at 262.89 267.97 0)
      (effects (font (size 1.524 1.524)) (justify left) hide)
    )
    (property "Author" "Antmicro" (at 214.63 285.75 0)
      (effects (font (size 1.27 1.27) (thickness 0.15)) (justify left bottom) hide)
    )
    (property "License" "Apache-2.0" (at 212.09 285.75 0)
      (effects (font (size 1.27 1.27) (thickness 0.15)) (justify left bottom) hide)
    )
    (pin "1")
    (pin "2")
    (pin "3")
    (instances
      (project "ecp5-dc-scm"
        (path ""
          (reference "Q3") (unit 1)
        )
      )
    )
  )

  (symbol (lib_id "antmicroResistors0402:R_1k1_0402") (at 255.27 270.51 0) (unit 1)
    (in_bom yes) (on_board yes) (dnp no) (fields_autoplaced)
    (property "Reference" "R71" (at 257.81 264.16 0)
      (effects (font (size 1.524 1.524)))
    )
    (property "Value" "R_1k1_0402" (at 255.27 274.32 0)
      (effects (font (size 1.524 1.524)) hide)
    )
    (property "Footprint" "antmicro-footprints:R_0402_1005Metric" (at 260.35 265.43 0)
      (effects (font (size 1.524 1.524)) (justify left) hide)
    )
    (property "Datasheet" "https://www.bourns.com/docs/product-datasheets/cr.pdf" (at 255.27 270.51 0)
      (effects (font (size 1.27 1.27)) hide)
    )
    (property "Manufacturer" "Bourns" (at 260.35 260.35 0)
      (effects (font (size 1.524 1.524)) (justify left) hide)
    )
    (property "MPN" "CR0402-FX-1101GLF" (at 260.35 262.89 0)
      (effects (font (size 1.524 1.524)) (justify left) hide)
    )
    (property "Val" "1k1" (at 257.81 266.7 0)
      (effects (font (size 1.27 1.27)))
    )
    (property "License" "Apache-2.0" (at 275.59 295.91 0)
      (effects (font (size 1.27 1.27) (thickness 0.15)) (justify left bottom) hide)
    )
    (property "Author" "Antmicro" (at 275.59 298.45 0)
      (effects (font (size 1.27 1.27) (thickness 0.15)) (justify left bottom) hide)
    )
    (property "Tolerance" "1%" (at 275.59 280.67 0)
      (effects (font (size 1.27 1.27)) (justify left bottom) hide)
    )
    (property "Public" "False" (at 275.59 300.99 0)
      (effects (font (size 1.27 1.27)) (justify left bottom) hide)
    )
    (pin "1")
    (pin "2")
    (instances
      (project "ecp5-dc-scm"
        (path ""
          (reference "R71") (unit 1)
        )
      )
    )
  )

  (symbol (lib_id "antmicropower:GND") (at 226.06 273.05 0) (unit 1)
    (in_bom yes) (on_board yes) (dnp no)
    (property "Reference" "#PWR040" (at 226.06 279.4 0)
      (effects (font (size 1.27 1.27)) hide)
    )
    (property "Value" "GND" (at 226.187 277.4442 0)
      (effects (font (size 1.27 1.27)))
    )
    (property "Footprint" "" (at 226.06 273.05 0)
      (effects (font (size 1.27 1.27)) hide)
    )
    (property "Datasheet" "" (at 226.06 273.05 0)
      (effects (font (size 1.27 1.27)) hide)
    )
    (property "Author" "Antmicro" (at 234.95 280.67 0)
      (effects (font (size 1.27 1.27) (thickness 0.15)) (justify left bottom) hide)
    )
    (property "License" "Apache-2.0" (at 234.95 283.21 0)
      (effects (font (size 1.27 1.27) (thickness 0.15)) (justify left bottom) hide)
    )
    (pin "1")
    (instances
      (project "ecp5-dc-scm"
        (path ""
          (reference "#PWR040") (unit 1)
        )
      )
    )
  )

  (symbol (lib_id "antmicroCapacitors0402:C_100n_0402") (at 325.12 43.18 270) (unit 1)
    (in_bom yes) (on_board yes) (dnp no)
    (property "Reference" "C62" (at 331.47 44.45 90)
      (effects (font (size 1.524 1.524)) (justify right))
    )
    (property "Value" "C_100n_0402" (at 321.31 43.18 0)
      (effects (font (size 1.524 1.524)) hide)
    )
    (property "Footprint" "antmicro-footprints:C_0402_1005Metric" (at 330.2 48.26 0)
      (effects (font (size 1.524 1.524)) (justify left) hide)
    )
    (property "Datasheet" "https://www.murata.com/products/productdetail?partno=GRM155R61H104KE14%23" (at 325.12 43.18 0)
      (effects (font (size 1.27 1.27)) hide)
    )
    (property "Manufacturer" "Murata" (at 335.28 48.26 0)
      (effects (font (size 1.524 1.524)) (justify left) hide)
    )
    (property "MPN" "GRM155R61H104KE14D" (at 332.74 48.26 0)
      (effects (font (size 1.524 1.524)) (justify left) hide)
    )
    (property "Val" "100n" (at 331.47 46.99 90)
      (effects (font (size 1.27 1.27)) (justify right))
    )
    (property "License" "Apache-2.0" (at 302.26 63.5 0)
      (effects (font (size 1.27 1.27) (thickness 0.15)) (justify left bottom) hide)
    )
    (property "Author" "Antmicro" (at 299.72 63.5 0)
      (effects (font (size 1.27 1.27) (thickness 0.15)) (justify left bottom) hide)
    )
    (property "Voltage" "50V" (at 297.18 63.5 0)
      (effects (font (size 1.27 1.27)) (justify left bottom) hide)
    )
    (property "Dielectric" "X5R" (at 294.64 63.5 0)
      (effects (font (size 1.27 1.27)) (justify left bottom) hide)
    )
    (property "Public" "False" (at 292.1 63.5 0)
      (effects (font (size 1.27 1.27)) (justify left bottom) hide)
    )
    (pin "1")
    (pin "2")
    (instances
      (project "ecp5-dc-scm"
        (path ""
          (reference "C62") (unit 1)
        )
      )
    )
  )

  (symbol (lib_id "antmicroCapacitors0402:C_100n_0402") (at 298.45 43.18 270) (unit 1)
    (in_bom yes) (on_board yes) (dnp no) (fields_autoplaced)
    (property "Reference" "C64" (at 300.99 44.4563 90)
      (effects (font (size 1.524 1.524)) (justify left))
    )
    (property "Value" "C_100n_0402" (at 294.64 43.18 0)
      (effects (font (size 1.524 1.524)) hide)
    )
    (property "Footprint" "antmicro-footprints:C_0402_1005Metric" (at 303.53 48.26 0)
      (effects (font (size 1.524 1.524)) (justify left) hide)
    )
    (property "Datasheet" "https://www.murata.com/products/productdetail?partno=GRM155R61H104KE14%23" (at 298.45 43.18 0)
      (effects (font (size 1.27 1.27)) hide)
    )
    (property "Manufacturer" "Murata" (at 308.61 48.26 0)
      (effects (font (size 1.524 1.524)) (justify left) hide)
    )
    (property "MPN" "GRM155R61H104KE14D" (at 306.07 48.26 0)
      (effects (font (size 1.524 1.524)) (justify left) hide)
    )
    (property "Val" "100n" (at 300.99 46.9963 90)
      (effects (font (size 1.27 1.27)) (justify left))
    )
    (property "License" "Apache-2.0" (at 275.59 63.5 0)
      (effects (font (size 1.27 1.27) (thickness 0.15)) (justify left bottom) hide)
    )
    (property "Author" "Antmicro" (at 273.05 63.5 0)
      (effects (font (size 1.27 1.27) (thickness 0.15)) (justify left bottom) hide)
    )
    (property "Voltage" "50V" (at 270.51 63.5 0)
      (effects (font (size 1.27 1.27)) (justify left bottom) hide)
    )
    (property "Dielectric" "X5R" (at 267.97 63.5 0)
      (effects (font (size 1.27 1.27)) (justify left bottom) hide)
    )
    (property "Public" "False" (at 265.43 63.5 0)
      (effects (font (size 1.27 1.27)) (justify left bottom) hide)
    )
    (pin "1")
    (pin "2")
    (instances
      (project "ecp5-dc-scm"
        (path ""
          (reference "C64") (unit 1)
        )
      )
    )
  )

  (symbol (lib_id "antmicroCapacitors0402:C_100n_0402") (at 307.34 43.18 270) (unit 1)
    (in_bom yes) (on_board yes) (dnp no) (fields_autoplaced)
    (property "Reference" "C67" (at 309.88 44.4563 90)
      (effects (font (size 1.524 1.524)) (justify left))
    )
    (property "Value" "C_100n_0402" (at 303.53 43.18 0)
      (effects (font (size 1.524 1.524)) hide)
    )
    (property "Footprint" "antmicro-footprints:C_0402_1005Metric" (at 312.42 48.26 0)
      (effects (font (size 1.524 1.524)) (justify left) hide)
    )
    (property "Datasheet" "https://www.murata.com/products/productdetail?partno=GRM155R61H104KE14%23" (at 307.34 43.18 0)
      (effects (font (size 1.27 1.27)) hide)
    )
    (property "Manufacturer" "Murata" (at 317.5 48.26 0)
      (effects (font (size 1.524 1.524)) (justify left) hide)
    )
    (property "MPN" "GRM155R61H104KE14D" (at 314.96 48.26 0)
      (effects (font (size 1.524 1.524)) (justify left) hide)
    )
    (property "Val" "100n" (at 309.88 46.9963 90)
      (effects (font (size 1.27 1.27)) (justify left))
    )
    (property "License" "Apache-2.0" (at 284.48 63.5 0)
      (effects (font (size 1.27 1.27) (thickness 0.15)) (justify left bottom) hide)
    )
    (property "Author" "Antmicro" (at 281.94 63.5 0)
      (effects (font (size 1.27 1.27) (thickness 0.15)) (justify left bottom) hide)
    )
    (property "Voltage" "50V" (at 279.4 63.5 0)
      (effects (font (size 1.27 1.27)) (justify left bottom) hide)
    )
    (property "Dielectric" "X5R" (at 276.86 63.5 0)
      (effects (font (size 1.27 1.27)) (justify left bottom) hide)
    )
    (property "Public" "False" (at 274.32 63.5 0)
      (effects (font (size 1.27 1.27)) (justify left bottom) hide)
    )
    (pin "1")
    (pin "2")
    (instances
      (project "ecp5-dc-scm"
        (path ""
          (reference "C67") (unit 1)
        )
      )
    )
  )

  (symbol (lib_id "antmicroCapacitors0402:C_100n_0402") (at 316.23 43.18 270) (unit 1)
    (in_bom yes) (on_board yes) (dnp no) (fields_autoplaced)
    (property "Reference" "C69" (at 318.77 44.4563 90)
      (effects (font (size 1.524 1.524)) (justify left))
    )
    (property "Value" "C_100n_0402" (at 312.42 43.18 0)
      (effects (font (size 1.524 1.524)) hide)
    )
    (property "Footprint" "antmicro-footprints:C_0402_1005Metric" (at 321.31 48.26 0)
      (effects (font (size 1.524 1.524)) (justify left) hide)
    )
    (property "Datasheet" "https://www.murata.com/products/productdetail?partno=GRM155R61H104KE14%23" (at 316.23 43.18 0)
      (effects (font (size 1.27 1.27)) hide)
    )
    (property "Manufacturer" "Murata" (at 326.39 48.26 0)
      (effects (font (size 1.524 1.524)) (justify left) hide)
    )
    (property "MPN" "GRM155R61H104KE14D" (at 323.85 48.26 0)
      (effects (font (size 1.524 1.524)) (justify left) hide)
    )
    (property "Val" "100n" (at 318.77 46.9963 90)
      (effects (font (size 1.27 1.27)) (justify left))
    )
    (property "License" "Apache-2.0" (at 293.37 63.5 0)
      (effects (font (size 1.27 1.27) (thickness 0.15)) (justify left bottom) hide)
    )
    (property "Author" "Antmicro" (at 290.83 63.5 0)
      (effects (font (size 1.27 1.27) (thickness 0.15)) (justify left bottom) hide)
    )
    (property "Voltage" "50V" (at 288.29 63.5 0)
      (effects (font (size 1.27 1.27)) (justify left bottom) hide)
    )
    (property "Dielectric" "X5R" (at 285.75 63.5 0)
      (effects (font (size 1.27 1.27)) (justify left bottom) hide)
    )
    (property "Public" "False" (at 283.21 63.5 0)
      (effects (font (size 1.27 1.27)) (justify left bottom) hide)
    )
    (pin "1")
    (pin "2")
    (instances
      (project "ecp5-dc-scm"
        (path ""
          (reference "C69") (unit 1)
        )
      )
    )
  )

  (symbol (lib_id "antmicroCapacitors0402:C_4u7_0402") (at 289.56 48.26 90) (unit 1)
    (in_bom yes) (on_board yes) (dnp no) (fields_autoplaced)
    (property "Reference" "C72" (at 292.1 44.4436 90)
      (effects (font (size 1.524 1.524)) (justify right))
    )
    (property "Value" "C_4u7_0402" (at 293.37 48.26 0)
      (effects (font (size 1.524 1.524)) hide)
    )
    (property "Footprint" "antmicro-footprints:C_0402_1005Metric" (at 284.48 43.18 0)
      (effects (font (size 1.524 1.524)) (justify left) hide)
    )
    (property "Datasheet" "https://www.murata.com/products/productdetail?partno=GRM155R61A475MEAA%23" (at 289.56 48.26 0)
      (effects (font (size 1.27 1.27)) hide)
    )
    (property "Manufacturer" "Murata" (at 279.4 43.18 0)
      (effects (font (size 1.524 1.524)) (justify left) hide)
    )
    (property "MPN" "GRM155R61A475MEAAD" (at 281.94 43.18 0)
      (effects (font (size 1.524 1.524)) (justify left) hide)
    )
    (property "Val" "4u7" (at 292.1 46.9836 90)
      (effects (font (size 1.27 1.27)) (justify right))
    )
    (property "License" "Apache-2.0" (at 312.42 27.94 0)
      (effects (font (size 1.27 1.27) (thickness 0.15)) (justify left bottom) hide)
    )
    (property "Author" "Antmicro" (at 314.96 27.94 0)
      (effects (font (size 1.27 1.27) (thickness 0.15)) (justify left bottom) hide)
    )
    (property "Voltage" "" (at 317.5 27.94 0)
      (effects (font (size 1.27 1.27)) (justify left bottom) hide)
    )
    (property "Dielectric" "" (at 320.04 27.94 0)
      (effects (font (size 1.27 1.27)) (justify left bottom) hide)
    )
    (property "Public" "False" (at 322.58 27.94 0)
      (effects (font (size 1.27 1.27)) (justify left bottom) hide)
    )
    (pin "1")
    (pin "2")
    (instances
      (project "ecp5-dc-scm"
        (path ""
          (reference "C72") (unit 1)
        )
      )
    )
  )

  (symbol (lib_id "antmicroCapacitors0402:C_100n_0402") (at 396.24 49.53 270) (unit 1)
    (in_bom yes) (on_board yes) (dnp no) (fields_autoplaced)
    (property "Reference" "C74" (at 393.065 50.8063 90)
      (effects (font (size 1.524 1.524)) (justify right))
    )
    (property "Value" "C_100n_0402" (at 392.43 49.53 0)
      (effects (font (size 1.524 1.524)) hide)
    )
    (property "Footprint" "antmicro-footprints:C_0402_1005Metric" (at 401.32 54.61 0)
      (effects (font (size 1.524 1.524)) (justify left) hide)
    )
    (property "Datasheet" "https://www.murata.com/products/productdetail?partno=GRM155R61H104KE14%23" (at 396.24 49.53 0)
      (effects (font (size 1.27 1.27)) hide)
    )
    (property "Manufacturer" "Murata" (at 406.4 54.61 0)
      (effects (font (size 1.524 1.524)) (justify left) hide)
    )
    (property "MPN" "GRM155R61H104KE14D" (at 403.86 54.61 0)
      (effects (font (size 1.524 1.524)) (justify left) hide)
    )
    (property "Val" "100n" (at 393.065 53.3463 90)
      (effects (font (size 1.27 1.27)) (justify right))
    )
    (property "License" "Apache-2.0" (at 373.38 69.85 0)
      (effects (font (size 1.27 1.27) (thickness 0.15)) (justify left bottom) hide)
    )
    (property "Author" "Antmicro" (at 370.84 69.85 0)
      (effects (font (size 1.27 1.27) (thickness 0.15)) (justify left bottom) hide)
    )
    (property "Voltage" "50V" (at 368.3 69.85 0)
      (effects (font (size 1.27 1.27)) (justify left bottom) hide)
    )
    (property "Dielectric" "X5R" (at 365.76 69.85 0)
      (effects (font (size 1.27 1.27)) (justify left bottom) hide)
    )
    (property "Public" "False" (at 363.22 69.85 0)
      (effects (font (size 1.27 1.27)) (justify left bottom) hide)
    )
    (pin "1")
    (pin "2")
    (instances
      (project "ecp5-dc-scm"
        (path ""
          (reference "C74") (unit 1)
        )
      )
    )
  )

  (symbol (lib_id "antmicroCapacitors0402:C_100n_0402") (at 394.97 36.83 270) (mirror x) (unit 1)
    (in_bom yes) (on_board yes) (dnp no) (fields_autoplaced)
    (property "Reference" "C76" (at 392.43 33.0136 90)
      (effects (font (size 1.524 1.524)) (justify right))
    )
    (property "Value" "C_100n_0402" (at 391.16 36.83 0)
      (effects (font (size 1.524 1.524)) hide)
    )
    (property "Footprint" "antmicro-footprints:C_0402_1005Metric" (at 400.05 31.75 0)
      (effects (font (size 1.524 1.524)) (justify left) hide)
    )
    (property "Datasheet" "https://www.murata.com/products/productdetail?partno=GRM155R61H104KE14%23" (at 394.97 36.83 0)
      (effects (font (size 1.27 1.27)) hide)
    )
    (property "Manufacturer" "Murata" (at 405.13 31.75 0)
      (effects (font (size 1.524 1.524)) (justify left) hide)
    )
    (property "MPN" "GRM155R61H104KE14D" (at 402.59 31.75 0)
      (effects (font (size 1.524 1.524)) (justify left) hide)
    )
    (property "Val" "100n" (at 392.43 35.5536 90)
      (effects (font (size 1.27 1.27)) (justify right))
    )
    (property "License" "Apache-2.0" (at 372.11 16.51 0)
      (effects (font (size 1.27 1.27) (thickness 0.15)) (justify left bottom) hide)
    )
    (property "Author" "Antmicro" (at 369.57 16.51 0)
      (effects (font (size 1.27 1.27) (thickness 0.15)) (justify left bottom) hide)
    )
    (property "Voltage" "50V" (at 367.03 16.51 0)
      (effects (font (size 1.27 1.27)) (justify left bottom) hide)
    )
    (property "Dielectric" "X5R" (at 364.49 16.51 0)
      (effects (font (size 1.27 1.27)) (justify left bottom) hide)
    )
    (property "Public" "False" (at 361.95 16.51 0)
      (effects (font (size 1.27 1.27)) (justify left bottom) hide)
    )
    (pin "1")
    (pin "2")
    (instances
      (project "ecp5-dc-scm"
        (path ""
          (reference "C76") (unit 1)
        )
      )
    )
  )

  (symbol (lib_id "antmicroCapacitors0402:C_4u7_0402") (at 405.13 48.26 270) (unit 1)
    (in_bom yes) (on_board yes) (dnp no)
    (property "Reference" "C70" (at 398.78 49.53 90)
      (effects (font (size 1.524 1.524)) (justify left))
    )
    (property "Value" "C_4u7_0402" (at 401.32 48.26 0)
      (effects (font (size 1.524 1.524)) hide)
    )
    (property "Footprint" "antmicro-footprints:C_0402_1005Metric" (at 410.21 53.34 0)
      (effects (font (size 1.524 1.524)) (justify left) hide)
    )
    (property "Datasheet" "https://www.murata.com/products/productdetail?partno=GRM155R61A475MEAA%23" (at 405.13 48.26 0)
      (effects (font (size 1.27 1.27)) hide)
    )
    (property "Manufacturer" "Murata" (at 415.29 53.34 0)
      (effects (font (size 1.524 1.524)) (justify left) hide)
    )
    (property "MPN" "GRM155R61A475MEAAD" (at 412.75 53.34 0)
      (effects (font (size 1.524 1.524)) (justify left) hide)
    )
    (property "Val" "4u7" (at 398.78 52.07 90)
      (effects (font (size 1.27 1.27)) (justify left))
    )
    (property "License" "Apache-2.0" (at 382.27 68.58 0)
      (effects (font (size 1.27 1.27) (thickness 0.15)) (justify left bottom) hide)
    )
    (property "Author" "Antmicro" (at 379.73 68.58 0)
      (effects (font (size 1.27 1.27) (thickness 0.15)) (justify left bottom) hide)
    )
    (property "Voltage" "" (at 377.19 68.58 0)
      (effects (font (size 1.27 1.27)) (justify left bottom) hide)
    )
    (property "Dielectric" "" (at 374.65 68.58 0)
      (effects (font (size 1.27 1.27)) (justify left bottom) hide)
    )
    (property "Public" "False" (at 372.11 68.58 0)
      (effects (font (size 1.27 1.27)) (justify left bottom) hide)
    )
    (pin "1")
    (pin "2")
    (instances
      (project "ecp5-dc-scm"
        (path ""
          (reference "C70") (unit 1)
        )
      )
    )
  )

  (symbol (lib_id "antmicroCapacitors0402:C_4u7_0402") (at 403.86 36.83 90) (unit 1)
    (in_bom yes) (on_board yes) (dnp no)
    (property "Reference" "C77" (at 398.145 33.0264 90)
      (effects (font (size 1.524 1.524)) (justify right))
    )
    (property "Value" "C_4u7_0402" (at 407.67 36.83 0)
      (effects (font (size 1.524 1.524)) hide)
    )
    (property "Footprint" "antmicro-footprints:C_0402_1005Metric" (at 398.78 31.75 0)
      (effects (font (size 1.524 1.524)) (justify left) hide)
    )
    (property "Datasheet" "https://www.murata.com/products/productdetail?partno=GRM155R61A475MEAA%23" (at 403.86 36.83 0)
      (effects (font (size 1.27 1.27)) hide)
    )
    (property "Manufacturer" "Murata" (at 393.7 31.75 0)
      (effects (font (size 1.524 1.524)) (justify left) hide)
    )
    (property "MPN" "GRM155R61A475MEAAD" (at 396.24 31.75 0)
      (effects (font (size 1.524 1.524)) (justify left) hide)
    )
    (property "Val" "4u7" (at 398.145 35.56 90)
      (effects (font (size 1.27 1.27)) (justify right))
    )
    (property "License" "Apache-2.0" (at 426.72 16.51 0)
      (effects (font (size 1.27 1.27) (thickness 0.15)) (justify left bottom) hide)
    )
    (property "Author" "Antmicro" (at 429.26 16.51 0)
      (effects (font (size 1.27 1.27) (thickness 0.15)) (justify left bottom) hide)
    )
    (property "Voltage" "" (at 431.8 16.51 0)
      (effects (font (size 1.27 1.27)) (justify left bottom) hide)
    )
    (property "Dielectric" "" (at 434.34 16.51 0)
      (effects (font (size 1.27 1.27)) (justify left bottom) hide)
    )
    (property "Public" "False" (at 436.88 16.51 0)
      (effects (font (size 1.27 1.27)) (justify left bottom) hide)
    )
    (pin "1")
    (pin "2")
    (instances
      (project "ecp5-dc-scm"
        (path ""
          (reference "C77") (unit 1)
        )
      )
    )
  )

  (symbol (lib_id "antmicropower:GND") (at 336.55 91.44 0) (mirror y) (unit 1)
    (in_bom yes) (on_board yes) (dnp no)
    (property "Reference" "#PWR048" (at 336.55 97.79 0)
      (effects (font (size 1.27 1.27)) hide)
    )
    (property "Value" "GND" (at 336.423 95.8342 0)
      (effects (font (size 1.27 1.27)))
    )
    (property "Footprint" "" (at 336.55 91.44 0)
      (effects (font (size 1.27 1.27)) hide)
    )
    (property "Datasheet" "" (at 336.55 91.44 0)
      (effects (font (size 1.27 1.27)) hide)
    )
    (property "Author" "Antmicro" (at 327.66 99.06 0)
      (effects (font (size 1.27 1.27) (thickness 0.15)) (justify left bottom) hide)
    )
    (property "License" "Apache-2.0" (at 327.66 101.6 0)
      (effects (font (size 1.27 1.27) (thickness 0.15)) (justify left bottom) hide)
    )
    (pin "1")
    (instances
      (project "ecp5-dc-scm"
        (path ""
          (reference "#PWR048") (unit 1)
        )
      )
    )
  )

  (symbol (lib_id "antmicroResistors0402:R_1k_0402") (at 335.28 62.23 0) (unit 1)
    (in_bom yes) (on_board yes) (dnp no) (fields_autoplaced)
    (property "Reference" "R76" (at 337.82 66.04 0)
      (effects (font (size 1.524 1.524)))
    )
    (property "Value" "R_1k_0402" (at 335.28 66.04 0)
      (effects (font (size 1.524 1.524)) hide)
    )
    (property "Footprint" "antmicro-footprints:R_0402_1005Metric" (at 340.36 57.15 0)
      (effects (font (size 1.524 1.524)) (justify left) hide)
    )
    (property "Datasheet" "https://www.bourns.com/docs/product-datasheets/cr.pdf" (at 335.28 62.23 0)
      (effects (font (size 1.27 1.27)) hide)
    )
    (property "Manufacturer" "Bourns" (at 340.36 52.07 0)
      (effects (font (size 1.524 1.524)) (justify left) hide)
    )
    (property "MPN" "CR0402-FX-1001GLF" (at 340.36 54.61 0)
      (effects (font (size 1.524 1.524)) (justify left) hide)
    )
    (property "Val" "1k" (at 337.82 68.58 0)
      (effects (font (size 1.27 1.27)))
    )
    (property "License" "Apache-2.0" (at 355.6 87.63 0)
      (effects (font (size 1.27 1.27) (thickness 0.15)) (justify left bottom) hide)
    )
    (property "Author" "Antmicro" (at 355.6 90.17 0)
      (effects (font (size 1.27 1.27) (thickness 0.15)) (justify left bottom) hide)
    )
    (property "Tolerance" "1%" (at 355.6 72.39 0)
      (effects (font (size 1.27 1.27)) (justify left bottom) hide)
    )
    (property "Public" "False" (at 355.6 92.71 0)
      (effects (font (size 1.27 1.27)) (justify left bottom) hide)
    )
    (pin "1")
    (pin "2")
    (instances
      (project "ecp5-dc-scm"
        (path ""
          (reference "R76") (unit 1)
        )
      )
    )
  )

  (symbol (lib_id "antmicroInterfaceControllers:USB3300-EZK-TR") (at 345.44 130.81 0) (unit 1)
    (in_bom yes) (on_board yes) (dnp no) (fields_autoplaced)
    (property "Reference" "U8" (at 357.505 123.19 0)
      (effects (font (size 1.27 1.27)))
    )
    (property "Value" "USB3300-EZK-TR" (at 357.505 125.73 0)
      (effects (font (size 1.27 1.27)))
    )
    (property "Footprint" "antmicro-footprints:QFN-32-1EP_5x5mm" (at 332.74 130.81 0)
      (effects (font (size 1.27 1.27)) (justify left bottom) hide)
    )
    (property "Datasheet" "https://ww1.microchip.com/downloads/en/DeviceDoc/00001783C.pdf" (at 345.44 130.81 0)
      (effects (font (size 1.27 1.27)) (justify left bottom) hide)
    )
    (property "Manufacturer" "Microchip Technology" (at 349.25 163.83 0)
      (effects (font (size 1.27 1.27)) (justify left bottom) hide)
    )
    (property "MPN" "USB3300-EZK-TR" (at 345.44 130.81 0)
      (effects (font (size 1.27 1.27)) hide)
    )
    (property "Author" "Antmicro" (at 383.54 148.59 0)
      (effects (font (size 1.27 1.27) (thickness 0.15)) (justify left bottom) hide)
    )
    (property "License" "Apache-2.0" (at 383.54 151.13 0)
      (effects (font (size 1.27 1.27) (thickness 0.15)) (justify left bottom) hide)
    )
    (pin "1")
    (pin "10")
    (pin "11")
    (pin "12")
    (pin "13")
    (pin "14")
    (pin "15")
    (pin "16")
    (pin "17")
    (pin "18")
    (pin "19")
    (pin "2")
    (pin "20")
    (pin "21")
    (pin "22")
    (pin "23")
    (pin "24")
    (pin "25")
    (pin "26")
    (pin "27")
    (pin "28")
    (pin "29")
    (pin "3")
    (pin "30")
    (pin "31")
    (pin "32")
    (pin "33")
    (pin "4")
    (pin "5")
    (pin "6")
    (pin "7")
    (pin "8")
    (pin "9")
    (instances
      (project "ecp5-dc-scm"
        (path ""
          (reference "U8") (unit 1)
        )
      )
    )
  )

  (symbol (lib_id "antmicroCapacitors0402:C_100n_0402") (at 331.47 119.38 270) (unit 1)
    (in_bom yes) (on_board yes) (dnp no)
    (property "Reference" "C60" (at 330.2 120.65 90)
      (effects (font (size 1.524 1.524)) (justify right))
    )
    (property "Value" "C_100n_0402" (at 327.66 119.38 0)
      (effects (font (size 1.524 1.524)) hide)
    )
    (property "Footprint" "antmicro-footprints:C_0402_1005Metric" (at 336.55 124.46 0)
      (effects (font (size 1.524 1.524)) (justify left) hide)
    )
    (property "Datasheet" "https://www.murata.com/products/productdetail?partno=GRM155R61H104KE14%23" (at 331.47 119.38 0)
      (effects (font (size 1.27 1.27)) hide)
    )
    (property "Manufacturer" "Murata" (at 341.63 124.46 0)
      (effects (font (size 1.524 1.524)) (justify left) hide)
    )
    (property "MPN" "GRM155R61H104KE14D" (at 339.09 124.46 0)
      (effects (font (size 1.524 1.524)) (justify left) hide)
    )
    (property "Val" "100n" (at 330.2 123.19 90)
      (effects (font (size 1.27 1.27)) (justify right))
    )
    (property "License" "Apache-2.0" (at 308.61 139.7 0)
      (effects (font (size 1.27 1.27) (thickness 0.15)) (justify left bottom) hide)
    )
    (property "Author" "Antmicro" (at 306.07 139.7 0)
      (effects (font (size 1.27 1.27) (thickness 0.15)) (justify left bottom) hide)
    )
    (property "Voltage" "50V" (at 303.53 139.7 0)
      (effects (font (size 1.27 1.27)) (justify left bottom) hide)
    )
    (property "Dielectric" "X5R" (at 300.99 139.7 0)
      (effects (font (size 1.27 1.27)) (justify left bottom) hide)
    )
    (property "Public" "False" (at 298.45 139.7 0)
      (effects (font (size 1.27 1.27)) (justify left bottom) hide)
    )
    (pin "1")
    (pin "2")
    (instances
      (project "ecp5-dc-scm"
        (path ""
          (reference "C60") (unit 1)
        )
      )
    )
  )

  (symbol (lib_id "antmicroCapacitors0402:C_100n_0402") (at 306.07 119.38 270) (unit 1)
    (in_bom yes) (on_board yes) (dnp no)
    (property "Reference" "C61" (at 299.72 120.65 90)
      (effects (font (size 1.524 1.524)) (justify left))
    )
    (property "Value" "C_100n_0402" (at 302.26 119.38 0)
      (effects (font (size 1.524 1.524)) hide)
    )
    (property "Footprint" "antmicro-footprints:C_0402_1005Metric" (at 311.15 124.46 0)
      (effects (font (size 1.524 1.524)) (justify left) hide)
    )
    (property "Datasheet" "https://www.murata.com/products/productdetail?partno=GRM155R61H104KE14%23" (at 306.07 119.38 0)
      (effects (font (size 1.27 1.27)) hide)
    )
    (property "Manufacturer" "Murata" (at 316.23 124.46 0)
      (effects (font (size 1.524 1.524)) (justify left) hide)
    )
    (property "MPN" "GRM155R61H104KE14D" (at 313.69 124.46 0)
      (effects (font (size 1.524 1.524)) (justify left) hide)
    )
    (property "Val" "100n" (at 299.72 123.19 90)
      (effects (font (size 1.27 1.27)) (justify left))
    )
    (property "License" "Apache-2.0" (at 283.21 139.7 0)
      (effects (font (size 1.27 1.27) (thickness 0.15)) (justify left bottom) hide)
    )
    (property "Author" "Antmicro" (at 280.67 139.7 0)
      (effects (font (size 1.27 1.27) (thickness 0.15)) (justify left bottom) hide)
    )
    (property "Voltage" "50V" (at 278.13 139.7 0)
      (effects (font (size 1.27 1.27)) (justify left bottom) hide)
    )
    (property "Dielectric" "X5R" (at 275.59 139.7 0)
      (effects (font (size 1.27 1.27)) (justify left bottom) hide)
    )
    (property "Public" "False" (at 273.05 139.7 0)
      (effects (font (size 1.27 1.27)) (justify left bottom) hide)
    )
    (pin "1")
    (pin "2")
    (instances
      (project "ecp5-dc-scm"
        (path ""
          (reference "C61") (unit 1)
        )
      )
    )
  )

  (symbol (lib_id "antmicroCapacitors0402:C_100n_0402") (at 314.96 119.38 270) (unit 1)
    (in_bom yes) (on_board yes) (dnp no)
    (property "Reference" "C63" (at 308.61 120.65 90)
      (effects (font (size 1.524 1.524)) (justify left))
    )
    (property "Value" "C_100n_0402" (at 311.15 119.38 0)
      (effects (font (size 1.524 1.524)) hide)
    )
    (property "Footprint" "antmicro-footprints:C_0402_1005Metric" (at 320.04 124.46 0)
      (effects (font (size 1.524 1.524)) (justify left) hide)
    )
    (property "Datasheet" "https://www.murata.com/products/productdetail?partno=GRM155R61H104KE14%23" (at 314.96 119.38 0)
      (effects (font (size 1.27 1.27)) hide)
    )
    (property "Manufacturer" "Murata" (at 325.12 124.46 0)
      (effects (font (size 1.524 1.524)) (justify left) hide)
    )
    (property "MPN" "GRM155R61H104KE14D" (at 322.58 124.46 0)
      (effects (font (size 1.524 1.524)) (justify left) hide)
    )
    (property "Val" "100n" (at 308.61 123.19 90)
      (effects (font (size 1.27 1.27)) (justify left))
    )
    (property "License" "Apache-2.0" (at 292.1 139.7 0)
      (effects (font (size 1.27 1.27) (thickness 0.15)) (justify left bottom) hide)
    )
    (property "Author" "Antmicro" (at 289.56 139.7 0)
      (effects (font (size 1.27 1.27) (thickness 0.15)) (justify left bottom) hide)
    )
    (property "Voltage" "50V" (at 287.02 139.7 0)
      (effects (font (size 1.27 1.27)) (justify left bottom) hide)
    )
    (property "Dielectric" "X5R" (at 284.48 139.7 0)
      (effects (font (size 1.27 1.27)) (justify left bottom) hide)
    )
    (property "Public" "False" (at 281.94 139.7 0)
      (effects (font (size 1.27 1.27)) (justify left bottom) hide)
    )
    (pin "1")
    (pin "2")
    (instances
      (project "ecp5-dc-scm"
        (path ""
          (reference "C63") (unit 1)
        )
      )
    )
  )

  (symbol (lib_id "antmicroCapacitors0402:C_100n_0402") (at 323.85 119.38 270) (unit 1)
    (in_bom yes) (on_board yes) (dnp no)
    (property "Reference" "C65" (at 317.5 120.65 90)
      (effects (font (size 1.524 1.524)) (justify left))
    )
    (property "Value" "C_100n_0402" (at 320.04 119.38 0)
      (effects (font (size 1.524 1.524)) hide)
    )
    (property "Footprint" "antmicro-footprints:C_0402_1005Metric" (at 328.93 124.46 0)
      (effects (font (size 1.524 1.524)) (justify left) hide)
    )
    (property "Datasheet" "https://www.murata.com/products/productdetail?partno=GRM155R61H104KE14%23" (at 323.85 119.38 0)
      (effects (font (size 1.27 1.27)) hide)
    )
    (property "Manufacturer" "Murata" (at 334.01 124.46 0)
      (effects (font (size 1.524 1.524)) (justify left) hide)
    )
    (property "MPN" "GRM155R61H104KE14D" (at 331.47 124.46 0)
      (effects (font (size 1.524 1.524)) (justify left) hide)
    )
    (property "Val" "100n" (at 317.5 123.19 90)
      (effects (font (size 1.27 1.27)) (justify left))
    )
    (property "License" "Apache-2.0" (at 300.99 139.7 0)
      (effects (font (size 1.27 1.27) (thickness 0.15)) (justify left bottom) hide)
    )
    (property "Author" "Antmicro" (at 298.45 139.7 0)
      (effects (font (size 1.27 1.27) (thickness 0.15)) (justify left bottom) hide)
    )
    (property "Voltage" "50V" (at 295.91 139.7 0)
      (effects (font (size 1.27 1.27)) (justify left bottom) hide)
    )
    (property "Dielectric" "X5R" (at 293.37 139.7 0)
      (effects (font (size 1.27 1.27)) (justify left bottom) hide)
    )
    (property "Public" "False" (at 290.83 139.7 0)
      (effects (font (size 1.27 1.27)) (justify left bottom) hide)
    )
    (pin "1")
    (pin "2")
    (instances
      (project "ecp5-dc-scm"
        (path ""
          (reference "C65") (unit 1)
        )
      )
    )
  )

  (symbol (lib_id "antmicroCapacitors0402:C_4u7_0402") (at 298.45 124.46 90) (unit 1)
    (in_bom yes) (on_board yes) (dnp no)
    (property "Reference" "C68" (at 292.1 120.65 90)
      (effects (font (size 1.524 1.524)) (justify right))
    )
    (property "Value" "C_4u7_0402" (at 302.26 124.46 0)
      (effects (font (size 1.524 1.524)) hide)
    )
    (property "Footprint" "antmicro-footprints:C_0402_1005Metric" (at 293.37 119.38 0)
      (effects (font (size 1.524 1.524)) (justify left) hide)
    )
    (property "Datasheet" "https://www.murata.com/products/productdetail?partno=GRM155R61A475MEAA%23" (at 298.45 124.46 0)
      (effects (font (size 1.27 1.27)) hide)
    )
    (property "Manufacturer" "Murata" (at 288.29 119.38 0)
      (effects (font (size 1.524 1.524)) (justify left) hide)
    )
    (property "MPN" "GRM155R61A475MEAAD" (at 290.83 119.38 0)
      (effects (font (size 1.524 1.524)) (justify left) hide)
    )
    (property "Val" "4u7" (at 292.1 123.19 90)
      (effects (font (size 1.27 1.27)) (justify right))
    )
    (property "License" "Apache-2.0" (at 321.31 104.14 0)
      (effects (font (size 1.27 1.27) (thickness 0.15)) (justify left bottom) hide)
    )
    (property "Author" "Antmicro" (at 323.85 104.14 0)
      (effects (font (size 1.27 1.27) (thickness 0.15)) (justify left bottom) hide)
    )
    (property "Voltage" "" (at 326.39 104.14 0)
      (effects (font (size 1.27 1.27)) (justify left bottom) hide)
    )
    (property "Dielectric" "" (at 328.93 104.14 0)
      (effects (font (size 1.27 1.27)) (justify left bottom) hide)
    )
    (property "Public" "False" (at 331.47 104.14 0)
      (effects (font (size 1.27 1.27)) (justify left bottom) hide)
    )
    (pin "1")
    (pin "2")
    (instances
      (project "ecp5-dc-scm"
        (path ""
          (reference "C68") (unit 1)
        )
      )
    )
  )

  (symbol (lib_id "antmicroCapacitors0402:C_100n_0402") (at 388.62 119.38 270) (unit 1)
    (in_bom yes) (on_board yes) (dnp no) (fields_autoplaced)
    (property "Reference" "C71" (at 391.16 120.6563 90)
      (effects (font (size 1.524 1.524)) (justify left))
    )
    (property "Value" "C_100n_0402" (at 384.81 119.38 0)
      (effects (font (size 1.524 1.524)) hide)
    )
    (property "Footprint" "antmicro-footprints:C_0402_1005Metric" (at 393.7 124.46 0)
      (effects (font (size 1.524 1.524)) (justify left) hide)
    )
    (property "Datasheet" "https://www.murata.com/products/productdetail?partno=GRM155R61H104KE14%23" (at 388.62 119.38 0)
      (effects (font (size 1.27 1.27)) hide)
    )
    (property "Manufacturer" "Murata" (at 398.78 124.46 0)
      (effects (font (size 1.524 1.524)) (justify left) hide)
    )
    (property "MPN" "GRM155R61H104KE14D" (at 396.24 124.46 0)
      (effects (font (size 1.524 1.524)) (justify left) hide)
    )
    (property "Val" "100n" (at 391.16 123.1963 90)
      (effects (font (size 1.27 1.27)) (justify left))
    )
    (property "License" "Apache-2.0" (at 365.76 139.7 0)
      (effects (font (size 1.27 1.27) (thickness 0.15)) (justify left bottom) hide)
    )
    (property "Author" "Antmicro" (at 363.22 139.7 0)
      (effects (font (size 1.27 1.27) (thickness 0.15)) (justify left bottom) hide)
    )
    (property "Voltage" "50V" (at 360.68 139.7 0)
      (effects (font (size 1.27 1.27)) (justify left bottom) hide)
    )
    (property "Dielectric" "X5R" (at 358.14 139.7 0)
      (effects (font (size 1.27 1.27)) (justify left bottom) hide)
    )
    (property "Public" "False" (at 355.6 139.7 0)
      (effects (font (size 1.27 1.27)) (justify left bottom) hide)
    )
    (pin "1")
    (pin "2")
    (instances
      (project "ecp5-dc-scm"
        (path ""
          (reference "C71") (unit 1)
        )
      )
    )
  )

  (symbol (lib_id "antmicroCapacitors0402:C_100n_0402") (at 388.62 139.7 270) (mirror x) (unit 1)
    (in_bom yes) (on_board yes) (dnp no) (fields_autoplaced)
    (property "Reference" "C73" (at 391.16 138.4237 90)
      (effects (font (size 1.524 1.524)) (justify left))
    )
    (property "Value" "C_100n_0402" (at 384.81 139.7 0)
      (effects (font (size 1.524 1.524)) hide)
    )
    (property "Footprint" "antmicro-footprints:C_0402_1005Metric" (at 393.7 134.62 0)
      (effects (font (size 1.524 1.524)) (justify left) hide)
    )
    (property "Datasheet" "https://www.murata.com/products/productdetail?partno=GRM155R61H104KE14%23" (at 388.62 139.7 0)
      (effects (font (size 1.27 1.27)) hide)
    )
    (property "Manufacturer" "Murata" (at 398.78 134.62 0)
      (effects (font (size 1.524 1.524)) (justify left) hide)
    )
    (property "MPN" "GRM155R61H104KE14D" (at 396.24 134.62 0)
      (effects (font (size 1.524 1.524)) (justify left) hide)
    )
    (property "Val" "100n" (at 391.16 135.8837 90)
      (effects (font (size 1.27 1.27)) (justify left))
    )
    (property "License" "Apache-2.0" (at 365.76 119.38 0)
      (effects (font (size 1.27 1.27) (thickness 0.15)) (justify left bottom) hide)
    )
    (property "Author" "Antmicro" (at 363.22 119.38 0)
      (effects (font (size 1.27 1.27) (thickness 0.15)) (justify left bottom) hide)
    )
    (property "Voltage" "50V" (at 360.68 119.38 0)
      (effects (font (size 1.27 1.27)) (justify left bottom) hide)
    )
    (property "Dielectric" "X5R" (at 358.14 119.38 0)
      (effects (font (size 1.27 1.27)) (justify left bottom) hide)
    )
    (property "Public" "False" (at 355.6 119.38 0)
      (effects (font (size 1.27 1.27)) (justify left bottom) hide)
    )
    (pin "1")
    (pin "2")
    (instances
      (project "ecp5-dc-scm"
        (path ""
          (reference "C73") (unit 1)
        )
      )
    )
  )

  (symbol (lib_id "antmicroCapacitors0402:C_4u7_0402") (at 397.51 139.7 270) (mirror x) (unit 1)
    (in_bom yes) (on_board yes) (dnp no) (fields_autoplaced)
    (property "Reference" "C66" (at 400.05 138.4237 90)
      (effects (font (size 1.524 1.524)) (justify left))
    )
    (property "Value" "C_4u7_0402" (at 393.7 139.7 0)
      (effects (font (size 1.524 1.524)) hide)
    )
    (property "Footprint" "antmicro-footprints:C_0402_1005Metric" (at 402.59 134.62 0)
      (effects (font (size 1.524 1.524)) (justify left) hide)
    )
    (property "Datasheet" "https://www.murata.com/products/productdetail?partno=GRM155R61A475MEAA%23" (at 397.51 139.7 0)
      (effects (font (size 1.27 1.27)) hide)
    )
    (property "Manufacturer" "Murata" (at 407.67 134.62 0)
      (effects (font (size 1.524 1.524)) (justify left) hide)
    )
    (property "MPN" "GRM155R61A475MEAAD" (at 405.13 134.62 0)
      (effects (font (size 1.524 1.524)) (justify left) hide)
    )
    (property "Val" "4u7" (at 400.05 135.8837 90)
      (effects (font (size 1.27 1.27)) (justify left))
    )
    (property "License" "Apache-2.0" (at 374.65 119.38 0)
      (effects (font (size 1.27 1.27) (thickness 0.15)) (justify left bottom) hide)
    )
    (property "Author" "Antmicro" (at 372.11 119.38 0)
      (effects (font (size 1.27 1.27) (thickness 0.15)) (justify left bottom) hide)
    )
    (property "Voltage" "" (at 369.57 119.38 0)
      (effects (font (size 1.27 1.27)) (justify left bottom) hide)
    )
    (property "Dielectric" "" (at 367.03 119.38 0)
      (effects (font (size 1.27 1.27)) (justify left bottom) hide)
    )
    (property "Public" "False" (at 364.49 119.38 0)
      (effects (font (size 1.27 1.27)) (justify left bottom) hide)
    )
    (pin "1")
    (pin "2")
    (instances
      (project "ecp5-dc-scm"
        (path ""
          (reference "C66") (unit 1)
        )
      )
    )
  )

  (symbol (lib_id "antmicroCapacitors0402:C_4u7_0402") (at 397.51 124.46 90) (unit 1)
    (in_bom yes) (on_board yes) (dnp no) (fields_autoplaced)
    (property "Reference" "C75" (at 400.05 120.6436 90)
      (effects (font (size 1.524 1.524)) (justify right))
    )
    (property "Value" "C_4u7_0402" (at 401.32 124.46 0)
      (effects (font (size 1.524 1.524)) hide)
    )
    (property "Footprint" "antmicro-footprints:C_0402_1005Metric" (at 392.43 119.38 0)
      (effects (font (size 1.524 1.524)) (justify left) hide)
    )
    (property "Datasheet" "https://www.murata.com/products/productdetail?partno=GRM155R61A475MEAA%23" (at 397.51 124.46 0)
      (effects (font (size 1.27 1.27)) hide)
    )
    (property "Manufacturer" "Murata" (at 387.35 119.38 0)
      (effects (font (size 1.524 1.524)) (justify left) hide)
    )
    (property "MPN" "GRM155R61A475MEAAD" (at 389.89 119.38 0)
      (effects (font (size 1.524 1.524)) (justify left) hide)
    )
    (property "Val" "4u7" (at 400.05 123.1836 90)
      (effects (font (size 1.27 1.27)) (justify right))
    )
    (property "License" "Apache-2.0" (at 420.37 104.14 0)
      (effects (font (size 1.27 1.27) (thickness 0.15)) (justify left bottom) hide)
    )
    (property "Author" "Antmicro" (at 422.91 104.14 0)
      (effects (font (size 1.27 1.27) (thickness 0.15)) (justify left bottom) hide)
    )
    (property "Voltage" "" (at 425.45 104.14 0)
      (effects (font (size 1.27 1.27)) (justify left bottom) hide)
    )
    (property "Dielectric" "" (at 427.99 104.14 0)
      (effects (font (size 1.27 1.27)) (justify left bottom) hide)
    )
    (property "Public" "False" (at 430.53 104.14 0)
      (effects (font (size 1.27 1.27)) (justify left bottom) hide)
    )
    (pin "1")
    (pin "2")
    (instances
      (project "ecp5-dc-scm"
        (path ""
          (reference "C75") (unit 1)
        )
      )
    )
  )

  (symbol (lib_id "antmicropower:GND") (at 335.28 179.07 0) (mirror y) (unit 1)
    (in_bom yes) (on_board yes) (dnp no)
    (property "Reference" "#PWR046" (at 335.28 185.42 0)
      (effects (font (size 1.27 1.27)) hide)
    )
    (property "Value" "GND" (at 335.153 183.4642 0)
      (effects (font (size 1.27 1.27)))
    )
    (property "Footprint" "" (at 335.28 179.07 0)
      (effects (font (size 1.27 1.27)) hide)
    )
    (property "Datasheet" "" (at 335.28 179.07 0)
      (effects (font (size 1.27 1.27)) hide)
    )
    (property "Author" "Antmicro" (at 326.39 186.69 0)
      (effects (font (size 1.27 1.27) (thickness 0.15)) (justify left bottom) hide)
    )
    (property "License" "Apache-2.0" (at 326.39 189.23 0)
      (effects (font (size 1.27 1.27) (thickness 0.15)) (justify left bottom) hide)
    )
    (pin "1")
    (instances
      (project "ecp5-dc-scm"
        (path ""
          (reference "#PWR046") (unit 1)
        )
      )
    )
  )

  (symbol (lib_id "antmicroResistors0402:R_1k_0402") (at 337.82 148.59 0) (unit 1)
    (in_bom yes) (on_board yes) (dnp no) (fields_autoplaced)
    (property "Reference" "R74" (at 340.36 152.4 0)
      (effects (font (size 1.524 1.524)))
    )
    (property "Value" "R_1k_0402" (at 337.82 152.4 0)
      (effects (font (size 1.524 1.524)) hide)
    )
    (property "Footprint" "antmicro-footprints:R_0402_1005Metric" (at 342.9 143.51 0)
      (effects (font (size 1.524 1.524)) (justify left) hide)
    )
    (property "Datasheet" "https://www.bourns.com/docs/product-datasheets/cr.pdf" (at 337.82 148.59 0)
      (effects (font (size 1.27 1.27)) hide)
    )
    (property "Manufacturer" "Bourns" (at 342.9 138.43 0)
      (effects (font (size 1.524 1.524)) (justify left) hide)
    )
    (property "MPN" "CR0402-FX-1001GLF" (at 342.9 140.97 0)
      (effects (font (size 1.524 1.524)) (justify left) hide)
    )
    (property "Val" "1k" (at 340.36 154.94 0)
      (effects (font (size 1.27 1.27)))
    )
    (property "License" "Apache-2.0" (at 358.14 173.99 0)
      (effects (font (size 1.27 1.27) (thickness 0.15)) (justify left bottom) hide)
    )
    (property "Author" "Antmicro" (at 358.14 176.53 0)
      (effects (font (size 1.27 1.27) (thickness 0.15)) (justify left bottom) hide)
    )
    (property "Tolerance" "1%" (at 358.14 158.75 0)
      (effects (font (size 1.27 1.27)) (justify left bottom) hide)
    )
    (property "Public" "False" (at 358.14 179.07 0)
      (effects (font (size 1.27 1.27)) (justify left bottom) hide)
    )
    (pin "1")
    (pin "2")
    (instances
      (project "ecp5-dc-scm"
        (path ""
          (reference "R74") (unit 1)
        )
      )
    )
  )

  (symbol (lib_id "antmicroOscillators:Oscillator_24MHz_ASEMB") (at 292.1 167.64 0) (unit 1)
    (in_bom yes) (on_board yes) (dnp no)
    (property "Reference" "Y3" (at 295.91 163.83 0)
      (effects (font (size 1.27 1.27) (thickness 0.15)))
    )
    (property "Value" "Oscillator_24MHz_ASEMB" (at 309.88 182.88 0)
      (effects (font (size 1.27 1.27) (thickness 0.15)) (justify left bottom) hide)
    )
    (property "Footprint" "antmicro-footprints:Oscillator_SMD_Abracon_ASEMB_3.2x2.5mm" (at 309.88 185.42 0)
      (effects (font (size 1.27 1.27) (thickness 0.15)) (justify left bottom) hide)
    )
    (property "Datasheet" "https://abracon.com/Oscillators/ASEMB.pdf" (at 309.88 187.96 0)
      (effects (font (size 1.27 1.27) (thickness 0.15)) (justify left bottom) hide)
    )
    (property "MPN" "ASEMB-24.000MHZ-LC-T" (at 306.07 176.53 0)
      (effects (font (size 1.27 1.27) (thickness 0.15)))
    )
    (property "Manufacturer" "Abracon" (at 309.88 177.8 0)
      (effects (font (size 1.27 1.27) (thickness 0.15)) (justify left bottom) hide)
    )
    (property "Val" "24 MHz" (at 304.8 163.83 0)
      (effects (font (size 1.27 1.27) (thickness 0.15)))
    )
    (property "Author" "Antmicro" (at 309.88 190.5 0)
      (effects (font (size 1.27 1.27) (thickness 0.15)) (justify left bottom) hide)
    )
    (property "License" "Apache-2.0" (at 309.88 193.04 0)
      (effects (font (size 1.27 1.27) (thickness 0.15)) (justify left bottom) hide)
    )
    (property "Public" "False" (at 323.85 191.77 0)
      (effects (font (size 1.27 1.27)) (justify left bottom) hide)
    )
    (pin "1")
    (pin "4")
    (pin "3")
    (pin "2")
    (instances
      (project "ecp5-dc-scm"
        (path ""
          (reference "Y3") (unit 1)
        )
      )
    )
  )

  (symbol (lib_id "antmicropower:GND") (at 290.83 173.99 0) (unit 1)
    (in_bom yes) (on_board yes) (dnp no)
    (property "Reference" "#PWR069" (at 290.83 180.34 0)
      (effects (font (size 1.27 1.27)) hide)
    )
    (property "Value" "GND" (at 290.957 178.3842 0)
      (effects (font (size 1.27 1.27)))
    )
    (property "Footprint" "" (at 290.83 173.99 0)
      (effects (font (size 1.27 1.27)) hide)
    )
    (property "Datasheet" "" (at 290.83 173.99 0)
      (effects (font (size 1.27 1.27)) hide)
    )
    (property "Author" "Antmicro" (at 299.72 181.61 0)
      (effects (font (size 1.27 1.27) (thickness 0.15)) (justify left bottom) hide)
    )
    (property "License" "Apache-2.0" (at 299.72 184.15 0)
      (effects (font (size 1.27 1.27) (thickness 0.15)) (justify left bottom) hide)
    )
    (pin "1")
    (instances
      (project "ecp5-dc-scm"
        (path ""
          (reference "#PWR069") (unit 1)
        )
      )
    )
  )

  (symbol (lib_id "antmicropower:GND") (at 403.86 39.37 0) (mirror y) (unit 1)
    (in_bom yes) (on_board yes) (dnp no)
    (property "Reference" "#PWR0128" (at 403.86 45.72 0)
      (effects (font (size 1.27 1.27)) hide)
    )
    (property "Value" "GND" (at 403.733 43.7642 0)
      (effects (font (size 1.27 1.27)))
    )
    (property "Footprint" "" (at 403.86 39.37 0)
      (effects (font (size 1.27 1.27)) hide)
    )
    (property "Datasheet" "" (at 403.86 39.37 0)
      (effects (font (size 1.27 1.27)) hide)
    )
    (property "Author" "Antmicro" (at 394.97 46.99 0)
      (effects (font (size 1.27 1.27) (thickness 0.15)) (justify left bottom) hide)
    )
    (property "License" "Apache-2.0" (at 394.97 49.53 0)
      (effects (font (size 1.27 1.27) (thickness 0.15)) (justify left bottom) hide)
    )
    (pin "1")
    (instances
      (project "ecp5-dc-scm"
        (path ""
          (reference "#PWR0128") (unit 1)
        )
      )
    )
  )

  (symbol (lib_id "antmicroTestPoints:TP_1mm_SMD") (at 238.76 129.54 0) (unit 1)
    (in_bom no) (on_board yes) (dnp no)
    (property "Reference" "TP15" (at 245.11 129.54 0)
      (effects (font (size 1.27 1.27) (thickness 0.15)))
    )
    (property "Value" "TP_1mm_SMD" (at 254 137.16 0)
      (effects (font (size 1.27 1.27) (thickness 0.15)) (justify left bottom) hide)
    )
    (property "Footprint" "antmicro-footprints:TP_SMD_1mm" (at 254 139.7 0)
      (effects (font (size 1.27 1.27) (thickness 0.15)) (justify left bottom) hide)
    )
    (property "Datasheet" "" (at 256.54 142.24 0)
      (effects (font (size 1.27 1.27) (thickness 0.15)) (justify left bottom) hide)
    )
    (property "MPN" "" (at 238.76 129.54 0)
      (effects (font (size 1.27 1.27)) hide)
    )
    (property "Manufacturer" "" (at 238.76 129.54 0)
      (effects (font (size 1.27 1.27)) hide)
    )
    (property "Author" "Antmicro" (at 254 144.78 0)
      (effects (font (size 1.27 1.27) (thickness 0.15)) (justify left bottom) hide)
    )
    (property "License" "Apache-2.0" (at 254 147.32 0)
      (effects (font (size 1.27 1.27) (thickness 0.15)) (justify left bottom) hide)
    )
    (pin "1")
    (instances
      (project "ecp5-dc-scm"
        (path ""
          (reference "TP15") (unit 1)
        )
      )
    )
  )

  (symbol (lib_name "LED_G_0603_LG_L29K-G2J1-24-Z_1") (lib_id "antmicroLEDIndicationDiscrete:LED_G_0603_LG_L29K-G2J1-24-Z") (at 246.38 270.51 0) (mirror x) (unit 1)
    (in_bom yes) (on_board yes) (dnp no)
    (property "Reference" "D5" (at 248.92 267.97 0)
      (effects (font (size 1.27 1.27) (thickness 0.15)))
    )
    (property "Value" "LED_G_0603_LG_L29K-G2J1-24-Z" (at 266.7 262.89 0)
      (effects (font (size 1.27 1.27) (thickness 0.15)) (justify left bottom) hide)
    )
    (property "Footprint" "antmicro-footprints:LED_0603_1608Metric_G" (at 266.7 260.35 0)
      (effects (font (size 1.27 1.27) (thickness 0.15)) (justify left bottom) hide)
    )
    (property "Datasheet" "https://look.ams-osram.com/m/19ee86b3ae0ee95b/original/LG-L29K.pdf" (at 266.7 257.81 0)
      (effects (font (size 1.27 1.27) (thickness 0.15)) (justify left bottom) hide)
    )
    (property "MPN" "LG L29K-G2J1-24-Z" (at 266.7 255.27 0)
      (effects (font (size 1.27 1.27) (thickness 0.15)) (justify left bottom) hide)
    )
    (property "Manufacturer" "OSRAM" (at 266.7 252.73 0)
      (effects (font (size 1.27 1.27) (thickness 0.15)) (justify left bottom) hide)
    )
    (property "Color" "Green" (at 248.92 274.32 0)
      (effects (font (size 1.27 1.27)))
    )
    (property "Author" "Antmicro" (at 266.7 250.19 0)
      (effects (font (size 1.27 1.27) (thickness 0.15)) (justify left bottom) hide)
    )
    (property "License" "Apache-2.0" (at 266.7 247.65 0)
      (effects (font (size 1.27 1.27) (thickness 0.15)) (justify left bottom) hide)
    )
    (pin "1")
    (pin "2")
    (instances
      (project "ecp5-dc-scm"
        (path ""
          (reference "D5") (unit 1)
        )
      )
    )
  )

  (symbol (lib_id "antmicropower:GND") (at 96.52 269.24 0) (mirror y) (unit 1)
    (in_bom yes) (on_board yes) (dnp no)
    (property "Reference" "#PWR065" (at 96.52 275.59 0)
      (effects (font (size 1.27 1.27)) hide)
    )
    (property "Value" "GND" (at 96.393 273.6342 0)
      (effects (font (size 1.27 1.27)))
    )
    (property "Footprint" "" (at 96.52 269.24 0)
      (effects (font (size 1.27 1.27)) hide)
    )
    (property "Datasheet" "" (at 96.52 269.24 0)
      (effects (font (size 1.27 1.27)) hide)
    )
    (property "Author" "Antmicro" (at 87.63 276.86 0)
      (effects (font (size 1.27 1.27) (thickness 0.15)) (justify left bottom) hide)
    )
    (property "License" "Apache-2.0" (at 87.63 279.4 0)
      (effects (font (size 1.27 1.27) (thickness 0.15)) (justify left bottom) hide)
    )
    (pin "1")
    (instances
      (project "ecp5-dc-scm"
        (path ""
          (reference "#PWR065") (unit 1)
        )
      )
    )
  )

  (symbol (lib_id "antmicropower:PWR_FLAG") (at 81.28 243.84 0) (unit 1)
    (in_bom yes) (on_board yes) (dnp no)
    (property "Reference" "#FLG020" (at 81.28 241.935 0)
      (effects (font (size 1.27 1.27)) hide)
    )
    (property "Value" "PWR_FLAG" (at 87.63 241.3 0)
      (effects (font (size 1.27 1.27)))
    )
    (property "Footprint" "" (at 81.28 243.84 0)
      (effects (font (size 1.27 1.27)) hide)
    )
    (property "Datasheet" "" (at 81.28 243.84 0)
      (effects (font (size 1.27 1.27)) hide)
    )
    (pin "1")
    (instances
      (project "ecp5-dc-scm"
        (path ""
          (reference "#FLG020") (unit 1)
        )
      )
    )
  )

  (symbol (lib_id "antmicroTestPoints:TP_1mm_SMD") (at 95.25 252.73 180) (unit 1)
    (in_bom no) (on_board yes) (dnp no)
    (property "Reference" "TP16" (at 88.9 252.73 0)
      (effects (font (size 1.27 1.27) (thickness 0.15)))
    )
    (property "Value" "TP_1mm_SMD" (at 80.01 245.11 0)
      (effects (font (size 1.27 1.27) (thickness 0.15)) (justify left bottom) hide)
    )
    (property "Footprint" "antmicro-footprints:TP_SMD_1mm" (at 80.01 242.57 0)
      (effects (font (size 1.27 1.27) (thickness 0.15)) (justify left bottom) hide)
    )
    (property "Datasheet" "" (at 77.47 240.03 0)
      (effects (font (size 1.27 1.27) (thickness 0.15)) (justify left bottom) hide)
    )
    (property "MPN" "" (at 95.25 252.73 0)
      (effects (font (size 1.27 1.27)) hide)
    )
    (property "Manufacturer" "" (at 95.25 252.73 0)
      (effects (font (size 1.27 1.27)) hide)
    )
    (property "Author" "Antmicro" (at 80.01 237.49 0)
      (effects (font (size 1.27 1.27) (thickness 0.15)) (justify left bottom) hide)
    )
    (property "License" "Apache-2.0" (at 80.01 234.95 0)
      (effects (font (size 1.27 1.27) (thickness 0.15)) (justify left bottom) hide)
    )
    (pin "1")
    (instances
      (project "ecp5-dc-scm"
        (path ""
          (reference "TP16") (unit 1)
        )
      )
    )
  )

  (symbol (lib_id "antmicroInterfaceControllers:USB3300-EZK-TR") (at 346.71 44.45 0) (unit 1)
    (in_bom yes) (on_board yes) (dnp no)
    (property "Reference" "U9" (at 350.52 40.64 0)
      (effects (font (size 1.27 1.27) (thickness 0.15)))
    )
    (property "Value" "USB3300-EZK-TR" (at 384.81 49.53 0)
      (effects (font (size 1.27 1.27) (thickness 0.15)) (justify left bottom) hide)
    )
    (property "Footprint" "antmicro-footprints:QFN-32-1EP_5x5mm" (at 384.81 52.07 0)
      (effects (font (size 1.27 1.27) (thickness 0.15)) (justify left bottom) hide)
    )
    (property "Datasheet" "https://ww1.microchip.com/downloads/en/DeviceDoc/00001783C.pdf" (at 384.81 54.61 0)
      (effects (font (size 1.27 1.27) (thickness 0.15)) (justify left bottom) hide)
    )
    (property "Manufacturer" "Microchip Technology" (at 384.81 57.15 0)
      (effects (font (size 1.27 1.27) (thickness 0.15)) (justify left bottom) hide)
    )
    (property "MPN" "USB3300-EZK-TR" (at 359.41 91.44 0)
      (effects (font (size 1.27 1.27) (thickness 0.15)))
    )
    (property "Author" "Antmicro" (at 384.81 62.23 0)
      (effects (font (size 1.27 1.27) (thickness 0.15)) (justify left bottom) hide)
    )
    (property "License" "Apache-2.0" (at 384.81 64.77 0)
      (effects (font (size 1.27 1.27) (thickness 0.15)) (justify left bottom) hide)
    )
    (pin "28")
    (pin "25")
    (pin "2")
    (pin "4")
    (pin "6")
    (pin "15")
    (pin "26")
    (pin "9")
    (pin "21")
    (pin "27")
    (pin "7")
    (pin "17")
    (pin "8")
    (pin "3")
    (pin "5")
    (pin "32")
    (pin "19")
    (pin "16")
    (pin "29")
    (pin "22")
    (pin "20")
    (pin "18")
    (pin "30")
    (pin "14")
    (pin "12")
    (pin "10")
    (pin "23")
    (pin "24")
    (pin "13")
    (pin "31")
    (pin "33")
    (pin "11")
    (pin "1")
    (instances
      (project "ecp5-dc-scm"
        (path ""
          (reference "U9") (unit 1)
        )
      )
    )
  )

  (symbol (lib_id "antmicropower:GND") (at 345.44 91.44 0) (mirror y) (unit 1)
    (in_bom yes) (on_board yes) (dnp no)
    (property "Reference" "#PWR050" (at 345.44 97.79 0)
      (effects (font (size 1.27 1.27)) hide)
    )
    (property "Value" "GND" (at 345.313 95.8342 0)
      (effects (font (size 1.27 1.27)))
    )
    (property "Footprint" "" (at 345.44 91.44 0)
      (effects (font (size 1.27 1.27)) hide)
    )
    (property "Datasheet" "" (at 345.44 91.44 0)
      (effects (font (size 1.27 1.27)) hide)
    )
    (property "Author" "Antmicro" (at 336.55 99.06 0)
      (effects (font (size 1.27 1.27) (thickness 0.15)) (justify left bottom) hide)
    )
    (property "License" "Apache-2.0" (at 336.55 101.6 0)
      (effects (font (size 1.27 1.27) (thickness 0.15)) (justify left bottom) hide)
    )
    (pin "1")
    (instances
      (project "ecp5-dc-scm"
        (path ""
          (reference "#PWR050") (unit 1)
        )
      )
    )
  )

  (symbol (lib_id "antmicropower:GND") (at 182.88 120.65 0) (unit 1)
    (in_bom yes) (on_board yes) (dnp no)
    (property "Reference" "#PWR049" (at 182.88 127 0)
      (effects (font (size 1.27 1.27)) hide)
    )
    (property "Value" "GND" (at 183.007 125.0442 0)
      (effects (font (size 1.27 1.27)))
    )
    (property "Footprint" "" (at 182.88 120.65 0)
      (effects (font (size 1.27 1.27)) hide)
    )
    (property "Datasheet" "" (at 182.88 120.65 0)
      (effects (font (size 1.27 1.27)) hide)
    )
    (property "Author" "Antmicro" (at 191.77 128.27 0)
      (effects (font (size 1.27 1.27) (thickness 0.15)) (justify left bottom) hide)
    )
    (property "License" "Apache-2.0" (at 191.77 130.81 0)
      (effects (font (size 1.27 1.27) (thickness 0.15)) (justify left bottom) hide)
    )
    (pin "1")
    (instances
      (project "ecp5-dc-scm"
        (path ""
          (reference "#PWR049") (unit 1)
        )
      )
    )
  )

  (symbol (lib_id "antmicroTestPoints:TP_1mm_SMD") (at 44.45 44.45 0) (unit 1)
    (in_bom no) (on_board yes) (dnp no)
    (property "Reference" "TP13" (at 50.8 44.45 0)
      (effects (font (size 1.27 1.27) (thickness 0.15)))
    )
    (property "Value" "TP_1mm_SMD" (at 59.69 52.07 0)
      (effects (font (size 1.27 1.27) (thickness 0.15)) (justify left bottom) hide)
    )
    (property "Footprint" "antmicro-footprints:TP_SMD_1mm" (at 59.69 54.61 0)
      (effects (font (size 1.27 1.27) (thickness 0.15)) (justify left bottom) hide)
    )
    (property "Datasheet" "" (at 62.23 57.15 0)
      (effects (font (size 1.27 1.27) (thickness 0.15)) (justify left bottom) hide)
    )
    (property "MPN" "" (at 44.45 44.45 0)
      (effects (font (size 1.27 1.27)) hide)
    )
    (property "Manufacturer" "" (at 44.45 44.45 0)
      (effects (font (size 1.27 1.27)) hide)
    )
    (property "Author" "Antmicro" (at 59.69 59.69 0)
      (effects (font (size 1.27 1.27) (thickness 0.15)) (justify left bottom) hide)
    )
    (property "License" "Apache-2.0" (at 59.69 62.23 0)
      (effects (font (size 1.27 1.27) (thickness 0.15)) (justify left bottom) hide)
    )
    (pin "1")
    (instances
      (project "ecp5-dc-scm"
        (path ""
          (reference "TP13") (unit 1)
        )
      )
    )
  )

  (symbol (lib_name "Oscillator_12MHz_ASFLMB_1") (lib_id "antmicroOscillators:Oscillator_12MHz_ASFLMB") (at 143.51 105.41 0) (unit 1)
    (in_bom yes) (on_board yes) (dnp no)
    (property "Reference" "Y4" (at 147.32 101.6 0)
      (effects (font (size 1.27 1.27) (thickness 0.15)))
    )
    (property "Value" "Oscillator_12MHz_ASFLMB" (at 168.91 117.475 0)
      (effects (font (size 1.27 1.27) (thickness 0.15)) (justify left bottom) hide)
    )
    (property "Footprint" "antmicro-footprints:Oscillator_SMD_Abracon_ASFLMB_5x3.2x0.85mm" (at 168.91 120.015 0)
      (effects (font (size 1.27 1.27) (thickness 0.15)) (justify left bottom) hide)
    )
    (property "Datasheet" "https://www.mouser.com/datasheet/2/3/ASFLMB-24525.pdf" (at 168.91 122.555 0)
      (effects (font (size 1.27 1.27) (thickness 0.15)) (justify left bottom) hide)
    )
    (property "MPN" "ASFLMB-12.000MHZ-LC-T" (at 157.48 114.3 0)
      (effects (font (size 1.27 1.27) (thickness 0.15)))
    )
    (property "Manufacturer" "Abracon" (at 168.91 112.395 0)
      (effects (font (size 1.27 1.27) (thickness 0.15)) (justify left bottom) hide)
    )
    (property "Val" "12 MHz" (at 156.21 101.6 0)
      (effects (font (size 1.27 1.27) (thickness 0.15)))
    )
    (property "Author" "Antmicro" (at 168.91 125.095 0)
      (effects (font (size 1.27 1.27) (thickness 0.15)) (justify left bottom) hide)
    )
    (property "License" "Apache-2.0" (at 168.91 127.635 0)
      (effects (font (size 1.27 1.27) (thickness 0.15)) (justify left bottom) hide)
    )
    (pin "2")
    (pin "3")
    (pin "4")
    (pin "1")
    (instances
      (project "ecp5-dc-scm"
        (path ""
          (reference "Y4") (unit 1)
        )
      )
    )
  )

  (symbol (lib_id "antmicropower:PWR_FLAG") (at 388.62 132.08 0) (unit 1)
    (in_bom yes) (on_board yes) (dnp no)
    (property "Reference" "#FLG022" (at 388.62 130.175 0)
      (effects (font (size 1.27 1.27)) hide)
    )
    (property "Value" "PWR_FLAG" (at 388.62 128.27 0)
      (effects (font (size 1.27 1.27)))
    )
    (property "Footprint" "" (at 388.62 132.08 0)
      (effects (font (size 1.27 1.27)) hide)
    )
    (property "Datasheet" "" (at 388.62 132.08 0)
      (effects (font (size 1.27 1.27)) hide)
    )
    (pin "1")
    (instances
      (project "ecp5-dc-scm"
        (path ""
          (reference "#FLG022") (unit 1)
        )
      )
    )
  )

  (symbol (lib_id "antmicropower:PWR_FLAG") (at 137.16 45.72 0) (unit 1)
    (in_bom yes) (on_board yes) (dnp no)
    (property "Reference" "#FLG017" (at 137.16 43.815 0)
      (effects (font (size 1.27 1.27)) hide)
    )
    (property "Value" "PWR_FLAG" (at 130.81 43.18 0)
      (effects (font (size 1.27 1.27)))
    )
    (property "Footprint" "" (at 137.16 45.72 0)
      (effects (font (size 1.27 1.27)) hide)
    )
    (property "Datasheet" "" (at 137.16 45.72 0)
      (effects (font (size 1.27 1.27)) hide)
    )
    (pin "1")
    (instances
      (project "ecp5-dc-scm"
        (path ""
          (reference "#FLG017") (unit 1)
        )
      )
    )
  )

  (symbol (lib_id "antmicropower:PWR_FLAG") (at 396.24 45.72 0) (unit 1)
    (in_bom yes) (on_board yes) (dnp no)
    (property "Reference" "#FLG012" (at 396.24 43.815 0)
      (effects (font (size 1.27 1.27)) hide)
    )
    (property "Value" "PWR_FLAG" (at 396.24 41.91 0)
      (effects (font (size 1.27 1.27)))
    )
    (property "Footprint" "" (at 396.24 45.72 0)
      (effects (font (size 1.27 1.27)) hide)
    )
    (property "Datasheet" "" (at 396.24 45.72 0)
      (effects (font (size 1.27 1.27)) hide)
    )
    (pin "1")
    (instances
      (project "ecp5-dc-scm"
        (path ""
          (reference "#FLG012") (unit 1)
        )
      )
    )
  )

  (symbol (lib_id "antmicroInterfaceControllers:FT4232H_VQFN") (at 196.85 39.37 0) (unit 1)
    (in_bom yes) (on_board yes) (dnp no)
    (property "Reference" "U14" (at 217.805 32.385 0)
      (effects (font (size 1.524 1.524)))
    )
    (property "Value" "FT4232H_VQFN" (at 217.805 34.925 0)
      (effects (font (size 1.524 1.524)))
    )
    (property "Footprint" "antmicro-footprints:QFN-56-1EP_8x8mm_P0.5mm" (at 201.93 34.29 90)
      (effects (font (size 1.524 1.524)) (justify left) hide)
    )
    (property "Datasheet" "https://www.ftdichip.com/Support/Documents/DataSheets/ICs/DS_FT4232H.pdf" (at 201.93 29.21 0)
      (effects (font (size 1.524 1.524)) (justify left) hide)
    )
    (property "Manufacturer" "FTDI Chip" (at 201.93 10.16 0)
      (effects (font (size 1.524 1.524)) (justify left) hide)
    )
    (property "MPN" "FT4232H-56Q-REEL" (at 201.93 25.4 0)
      (effects (font (size 1.524 1.524)) (justify left) hide)
    )
    (property "Author" "Antmicro" (at 252.73 57.15 0)
      (effects (font (size 1.27 1.27) (thickness 0.15)) (justify left bottom) hide)
    )
    (property "License" "Apache-2.0" (at 252.73 59.69 0)
      (effects (font (size 1.27 1.27) (thickness 0.15)) (justify left bottom) hide)
    )
    (pin "1")
    (pin "10")
    (pin "11")
    (pin "12")
    (pin "13")
    (pin "14")
    (pin "15")
    (pin "16")
    (pin "17")
    (pin "18")
    (pin "19")
    (pin "2")
    (pin "20")
    (pin "21")
    (pin "22")
    (pin "23")
    (pin "24")
    (pin "25")
    (pin "26")
    (pin "27")
    (pin "28")
    (pin "29")
    (pin "3")
    (pin "30")
    (pin "31")
    (pin "32")
    (pin "33")
    (pin "34")
    (pin "35")
    (pin "36")
    (pin "37")
    (pin "38")
    (pin "39")
    (pin "4")
    (pin "40")
    (pin "41")
    (pin "42")
    (pin "43")
    (pin "44")
    (pin "45")
    (pin "46")
    (pin "47")
    (pin "48")
    (pin "49")
    (pin "5")
    (pin "50")
    (pin "51")
    (pin "52")
    (pin "53")
    (pin "54")
    (pin "55")
    (pin "56")
    (pin "57")
    (pin "6")
    (pin "7")
    (pin "8")
    (pin "9")
    (instances
      (project "ecp5-dc-scm"
        (path ""
          (reference "U14") (unit 1)
        )
      )
    )
  )

  (symbol (lib_id "antmicropower:PWR_FLAG") (at 394.97 29.21 0) (unit 1)
    (in_bom yes) (on_board yes) (dnp no)
    (property "Reference" "#FLG011" (at 394.97 27.305 0)
      (effects (font (size 1.27 1.27)) hide)
    )
    (property "Value" "PWR_FLAG" (at 394.97 25.4 0)
      (effects (font (size 1.27 1.27)))
    )
    (property "Footprint" "" (at 394.97 29.21 0)
      (effects (font (size 1.27 1.27)) hide)
    )
    (property "Datasheet" "" (at 394.97 29.21 0)
      (effects (font (size 1.27 1.27)) hide)
    )
    (pin "1")
    (instances
      (project "ecp5-dc-scm"
        (path ""
          (reference "#FLG011") (unit 1)
        )
      )
    )
  )

  (symbol (lib_name "LED_G_0603_LG_L29K-G2J1-24-Z_1") (lib_id "antmicroLEDIndicationDiscrete:LED_G_0603_LG_L29K-G2J1-24-Z") (at 246.38 248.92 0) (mirror x) (unit 1)
    (in_bom yes) (on_board yes) (dnp no)
    (property "Reference" "D4" (at 248.92 246.38 0)
      (effects (font (size 1.27 1.27) (thickness 0.15)))
    )
    (property "Value" "LED_G_0603_LG_L29K-G2J1-24-Z" (at 266.7 241.3 0)
      (effects (font (size 1.27 1.27) (thickness 0.15)) (justify left bottom) hide)
    )
    (property "Footprint" "antmicro-footprints:LED_0603_1608Metric_G" (at 266.7 238.76 0)
      (effects (font (size 1.27 1.27) (thickness 0.15)) (justify left bottom) hide)
    )
    (property "Datasheet" "https://look.ams-osram.com/m/19ee86b3ae0ee95b/original/LG-L29K.pdf" (at 266.7 236.22 0)
      (effects (font (size 1.27 1.27) (thickness 0.15)) (justify left bottom) hide)
    )
    (property "MPN" "LG L29K-G2J1-24-Z" (at 266.7 233.68 0)
      (effects (font (size 1.27 1.27) (thickness 0.15)) (justify left bottom) hide)
    )
    (property "Manufacturer" "OSRAM" (at 266.7 231.14 0)
      (effects (font (size 1.27 1.27) (thickness 0.15)) (justify left bottom) hide)
    )
    (property "Color" "Green" (at 248.92 252.73 0)
      (effects (font (size 1.27 1.27)))
    )
    (property "Author" "Antmicro" (at 266.7 228.6 0)
      (effects (font (size 1.27 1.27) (thickness 0.15)) (justify left bottom) hide)
    )
    (property "License" "Apache-2.0" (at 266.7 226.06 0)
      (effects (font (size 1.27 1.27) (thickness 0.15)) (justify left bottom) hide)
    )
    (pin "1")
    (pin "2")
    (instances
      (project "ecp5-dc-scm"
        (path ""
          (reference "D4") (unit 1)
        )
      )
    )
  )

  (symbol (lib_id "antmicropower:PWR_FLAG") (at 156.21 59.69 0) (unit 1)
    (in_bom yes) (on_board yes) (dnp no)
    (property "Reference" "#FLG018" (at 156.21 57.785 0)
      (effects (font (size 1.27 1.27)) hide)
    )
    (property "Value" "PWR_FLAG" (at 156.21 55.88 0)
      (effects (font (size 1.27 1.27)))
    )
    (property "Footprint" "" (at 156.21 59.69 0)
      (effects (font (size 1.27 1.27)) hide)
    )
    (property "Datasheet" "" (at 156.21 59.69 0)
      (effects (font (size 1.27 1.27)) hide)
    )
    (pin "1")
    (instances
      (project "ecp5-dc-scm"
        (path ""
          (reference "#FLG018") (unit 1)
        )
      )
    )
  )

  (symbol (lib_id "antmicropower:GND") (at 194.31 134.62 0) (unit 1)
    (in_bom yes) (on_board yes) (dnp no)
    (property "Reference" "#PWR0106" (at 194.31 140.97 0)
      (effects (font (size 1.27 1.27)) hide)
    )
    (property "Value" "GND" (at 194.437 139.0142 0)
      (effects (font (size 1.27 1.27)))
    )
    (property "Footprint" "" (at 194.31 134.62 0)
      (effects (font (size 1.27 1.27)) hide)
    )
    (property "Datasheet" "" (at 194.31 134.62 0)
      (effects (font (size 1.27 1.27)) hide)
    )
    (property "Author" "Antmicro" (at 203.2 142.24 0)
      (effects (font (size 1.27 1.27) (thickness 0.15)) (justify left bottom) hide)
    )
    (property "License" "Apache-2.0" (at 203.2 144.78 0)
      (effects (font (size 1.27 1.27) (thickness 0.15)) (justify left bottom) hide)
    )
    (pin "1")
    (instances
      (project "ecp5-dc-scm"
        (path ""
          (reference "#PWR0106") (unit 1)
        )
      )
    )
  )

  (symbol (lib_id "antmicropower:PWR_FLAG") (at 97.79 160.02 0) (unit 1)
    (in_bom yes) (on_board yes) (dnp no)
    (property "Reference" "#FLG019" (at 97.79 158.115 0)
      (effects (font (size 1.27 1.27)) hide)
    )
    (property "Value" "PWR_FLAG" (at 97.79 156.21 0)
      (effects (font (size 1.27 1.27)))
    )
    (property "Footprint" "" (at 97.79 160.02 0)
      (effects (font (size 1.27 1.27)) hide)
    )
    (property "Datasheet" "" (at 97.79 160.02 0)
      (effects (font (size 1.27 1.27)) hide)
    )
    (pin "1")
    (instances
      (project "ecp5-dc-scm"
        (path ""
          (reference "#FLG019") (unit 1)
        )
      )
    )
  )

  (symbol (lib_id "antmicropower:GND") (at 397.51 127 0) (mirror y) (unit 1)
    (in_bom yes) (on_board yes) (dnp no)
    (property "Reference" "#PWR0103" (at 397.51 133.35 0)
      (effects (font (size 1.27 1.27)) hide)
    )
    (property "Value" "GND" (at 397.383 131.3942 0)
      (effects (font (size 1.27 1.27)))
    )
    (property "Footprint" "" (at 397.51 127 0)
      (effects (font (size 1.27 1.27)) hide)
    )
    (property "Datasheet" "" (at 397.51 127 0)
      (effects (font (size 1.27 1.27)) hide)
    )
    (property "Author" "Antmicro" (at 388.62 134.62 0)
      (effects (font (size 1.27 1.27) (thickness 0.15)) (justify left bottom) hide)
    )
    (property "License" "Apache-2.0" (at 388.62 137.16 0)
      (effects (font (size 1.27 1.27) (thickness 0.15)) (justify left bottom) hide)
    )
    (pin "1")
    (instances
      (project "ecp5-dc-scm"
        (path ""
          (reference "#PWR0103") (unit 1)
        )
      )
    )
  )

  (symbol (lib_id "antmicropower:GND") (at 344.17 180.34 0) (mirror y) (unit 1)
    (in_bom yes) (on_board yes) (dnp no)
    (property "Reference" "#PWR070" (at 344.17 186.69 0)
      (effects (font (size 1.27 1.27)) hide)
    )
    (property "Value" "GND" (at 344.043 184.7342 0)
      (effects (font (size 1.27 1.27)))
    )
    (property "Footprint" "" (at 344.17 180.34 0)
      (effects (font (size 1.27 1.27)) hide)
    )
    (property "Datasheet" "" (at 344.17 180.34 0)
      (effects (font (size 1.27 1.27)) hide)
    )
    (property "Author" "Antmicro" (at 335.28 187.96 0)
      (effects (font (size 1.27 1.27) (thickness 0.15)) (justify left bottom) hide)
    )
    (property "License" "Apache-2.0" (at 335.28 190.5 0)
      (effects (font (size 1.27 1.27) (thickness 0.15)) (justify left bottom) hide)
    )
    (pin "1")
    (instances
      (project "ecp5-dc-scm"
        (path ""
          (reference "#PWR070") (unit 1)
        )
      )
    )
  )

  (symbol (lib_id "antmicroTestPoints:TP_1mm_SMD") (at 238.76 127 0) (unit 1)
    (in_bom no) (on_board yes) (dnp no)
    (property "Reference" "TP14" (at 245.11 127 0)
      (effects (font (size 1.27 1.27) (thickness 0.15)))
    )
    (property "Value" "TP_1mm_SMD" (at 254 134.62 0)
      (effects (font (size 1.27 1.27) (thickness 0.15)) (justify left bottom) hide)
    )
    (property "Footprint" "antmicro-footprints:TP_SMD_1mm" (at 254 137.16 0)
      (effects (font (size 1.27 1.27) (thickness 0.15)) (justify left bottom) hide)
    )
    (property "Datasheet" "" (at 256.54 139.7 0)
      (effects (font (size 1.27 1.27) (thickness 0.15)) (justify left bottom) hide)
    )
    (property "MPN" "" (at 238.76 127 0)
      (effects (font (size 1.27 1.27)) hide)
    )
    (property "Manufacturer" "" (at 238.76 127 0)
      (effects (font (size 1.27 1.27)) hide)
    )
    (property "Author" "Antmicro" (at 254 142.24 0)
      (effects (font (size 1.27 1.27) (thickness 0.15)) (justify left bottom) hide)
    )
    (property "License" "Apache-2.0" (at 254 144.78 0)
      (effects (font (size 1.27 1.27) (thickness 0.15)) (justify left bottom) hide)
    )
    (pin "1")
    (instances
      (project "ecp5-dc-scm"
        (path ""
          (reference "TP14") (unit 1)
        )
      )
    )
  )

  (symbol (lib_id "antmicropower:GND") (at 142.24 113.03 0) (unit 1)
    (in_bom yes) (on_board yes) (dnp no)
    (property "Reference" "#PWR064" (at 142.24 119.38 0)
      (effects (font (size 1.27 1.27)) hide)
    )
    (property "Value" "GND" (at 142.367 117.4242 0)
      (effects (font (size 1.27 1.27)))
    )
    (property "Footprint" "" (at 142.24 113.03 0)
      (effects (font (size 1.27 1.27)) hide)
    )
    (property "Datasheet" "" (at 142.24 113.03 0)
      (effects (font (size 1.27 1.27)) hide)
    )
    (property "Author" "Antmicro" (at 151.13 120.65 0)
      (effects (font (size 1.27 1.27) (thickness 0.15)) (justify left bottom) hide)
    )
    (property "License" "Apache-2.0" (at 151.13 123.19 0)
      (effects (font (size 1.27 1.27) (thickness 0.15)) (justify left bottom) hide)
    )
    (pin "1")
    (instances
      (project "ecp5-dc-scm"
        (path ""
          (reference "#PWR064") (unit 1)
        )
      )
    )
  )

  (symbol (lib_name "LED_G_0603_LG_L29K-G2J1-24-Z_1") (lib_id "antmicroLEDIndicationDiscrete:LED_G_0603_LG_L29K-G2J1-24-Z") (at 246.38 224.79 0) (mirror x) (unit 1)
    (in_bom yes) (on_board yes) (dnp no)
    (property "Reference" "D3" (at 248.92 222.25 0)
      (effects (font (size 1.27 1.27) (thickness 0.15)))
    )
    (property "Value" "LED_G_0603_LG_L29K-G2J1-24-Z" (at 266.7 217.17 0)
      (effects (font (size 1.27 1.27) (thickness 0.15)) (justify left bottom) hide)
    )
    (property "Footprint" "antmicro-footprints:LED_0603_1608Metric_G" (at 266.7 214.63 0)
      (effects (font (size 1.27 1.27) (thickness 0.15)) (justify left bottom) hide)
    )
    (property "Datasheet" "https://look.ams-osram.com/m/19ee86b3ae0ee95b/original/LG-L29K.pdf" (at 266.7 212.09 0)
      (effects (font (size 1.27 1.27) (thickness 0.15)) (justify left bottom) hide)
    )
    (property "MPN" "LG L29K-G2J1-24-Z" (at 266.7 209.55 0)
      (effects (font (size 1.27 1.27) (thickness 0.15)) (justify left bottom) hide)
    )
    (property "Manufacturer" "OSRAM" (at 266.7 207.01 0)
      (effects (font (size 1.27 1.27) (thickness 0.15)) (justify left bottom) hide)
    )
    (property "Color" "Green" (at 248.92 228.6 0)
      (effects (font (size 1.27 1.27)))
    )
    (property "Author" "Antmicro" (at 266.7 204.47 0)
      (effects (font (size 1.27 1.27) (thickness 0.15)) (justify left bottom) hide)
    )
    (property "License" "Apache-2.0" (at 266.7 201.93 0)
      (effects (font (size 1.27 1.27) (thickness 0.15)) (justify left bottom) hide)
    )
    (pin "1")
    (pin "2")
    (instances
      (project "ecp5-dc-scm"
        (path ""
          (reference "D3") (unit 1)
        )
      )
    )
  )

  (symbol (lib_id "antmicropower:PWR_FLAG") (at 388.62 116.84 0) (unit 1)
    (in_bom yes) (on_board yes) (dnp no)
    (property "Reference" "#FLG021" (at 388.62 114.935 0)
      (effects (font (size 1.27 1.27)) hide)
    )
    (property "Value" "PWR_FLAG" (at 388.62 113.03 0)
      (effects (font (size 1.27 1.27)))
    )
    (property "Footprint" "" (at 388.62 116.84 0)
      (effects (font (size 1.27 1.27)) hide)
    )
    (property "Datasheet" "" (at 388.62 116.84 0)
      (effects (font (size 1.27 1.27)) hide)
    )
    (pin "1")
    (instances
      (project "ecp5-dc-scm"
        (path ""
          (reference "#FLG021") (unit 1)
        )
      )
    )
  )

  (symbol (lib_id "antmicropower:GND") (at 397.51 142.24 0) (mirror y) (unit 1)
    (in_bom yes) (on_board yes) (dnp no)
    (property "Reference" "#PWR072" (at 397.51 148.59 0)
      (effects (font (size 1.27 1.27)) hide)
    )
    (property "Value" "GND" (at 397.383 146.6342 0)
      (effects (font (size 1.27 1.27)))
    )
    (property "Footprint" "" (at 397.51 142.24 0)
      (effects (font (size 1.27 1.27)) hide)
    )
    (property "Datasheet" "" (at 397.51 142.24 0)
      (effects (font (size 1.27 1.27)) hide)
    )
    (property "Author" "Antmicro" (at 388.62 149.86 0)
      (effects (font (size 1.27 1.27) (thickness 0.15)) (justify left bottom) hide)
    )
    (property "License" "Apache-2.0" (at 388.62 152.4 0)
      (effects (font (size 1.27 1.27) (thickness 0.15)) (justify left bottom) hide)
    )
    (pin "1")
    (instances
      (project "ecp5-dc-scm"
        (path ""
          (reference "#PWR072") (unit 1)
        )
      )
    )
  )

  (symbol (lib_name "Oscillator_24MHz_ASEMB_1") (lib_id "antmicroOscillators:Oscillator_24MHz_ASEMB") (at 297.18 81.28 0) (unit 1)
    (in_bom yes) (on_board yes) (dnp no)
    (property "Reference" "Y2" (at 300.99 77.47 0)
      (effects (font (size 1.27 1.27) (thickness 0.15)))
    )
    (property "Value" "Oscillator_24MHz_ASEMB" (at 314.96 96.52 0)
      (effects (font (size 1.27 1.27) (thickness 0.15)) (justify left bottom) hide)
    )
    (property "Footprint" "antmicro-footprints:Oscillator_SMD_Abracon_ASEMB_3.2x2.5mm" (at 314.96 99.06 0)
      (effects (font (size 1.27 1.27) (thickness 0.15)) (justify left bottom) hide)
    )
    (property "Datasheet" "https://abracon.com/Oscillators/ASEMB.pdf" (at 314.96 101.6 0)
      (effects (font (size 1.27 1.27) (thickness 0.15)) (justify left bottom) hide)
    )
    (property "MPN" "ASEMB-24.000MHZ-LC-T" (at 311.15 90.17 0)
      (effects (font (size 1.27 1.27) (thickness 0.15)))
    )
    (property "Manufacturer" "Abracon" (at 314.96 91.44 0)
      (effects (font (size 1.27 1.27) (thickness 0.15)) (justify left bottom) hide)
    )
    (property "Val" "24 MHz" (at 309.88 77.47 0)
      (effects (font (size 1.27 1.27) (thickness 0.15)))
    )
    (property "Author" "Antmicro" (at 314.96 104.14 0)
      (effects (font (size 1.27 1.27) (thickness 0.15)) (justify left bottom) hide)
    )
    (property "License" "Apache-2.0" (at 314.96 106.68 0)
      (effects (font (size 1.27 1.27) (thickness 0.15)) (justify left bottom) hide)
    )
    (property "Public" "False" (at 328.93 105.41 0)
      (effects (font (size 1.27 1.27)) (justify left bottom) hide)
    )
    (pin "3")
    (pin "2")
    (pin "1")
    (pin "4")
    (instances
      (project "ecp5-dc-scm"
        (path ""
          (reference "Y2") (unit 1)
        )
      )
    )
  )
)
